G04 ================== begin FILE IDENTIFICATION RECORD ==================*
G04 Layout Name:  D:/<user>/Wistron_project/16315-1/gbr/16315-1.brd*
G04 Film Name:    L5*
G04 File Format:  Gerber RS274X*
G04 File Origin:  Cadence Allegro 16.5-S056*
G04 Origin Date:  Fri Jun 09 15:31:35 2017*
G04 *
G04 Layer:  VIA CLASS/L5*
G04 Layer:  PIN/L5*
G04 Layer:  ETCH/L5*
G04 Layer:  DRAWING FORMAT/LAYER_PCB_STORY*
G04 Layer:  DRAWING FORMAT/LAYER_L5*
G04 *
G04 Offset:    (0.00 0.00)*
G04 Mirror:    No*
G04 Mode:      Positive*
G04 Rotation:  0*
G04 FullContactRelief:  No*
G04 UndefLineWidth:     6.00*
G04 ================== end FILE IDENTIFICATION RECORD ====================*
%FSLAX35Y35*MOIN*%
%IR0*IPPOS*OFA0.00000B0.00000*MIA0B0*SFA1.00000B1.00000*%
%ADD12C,.03*%
%ADD11C,.022*%
%ADD13C,.034*%
%ADD10C,.028*%
%ADD14C,.048*%
%ADD15C,.01*%
%ADD16C,.02*%
%ADD17C,.006*%
%ADD18C,.00475*%
G75*
%LPD*%
G75*
G36*
G01X3937Y3004D02*
G02X3004Y3937I0J933D01*
G01Y12071D01*
G02X3714Y12323I400J0D01*
G03X7898Y8796I11444J9330D01*
G01X8000Y8739D01*
Y8000D01*
X9537D01*
X9574Y7985D01*
G03X20778Y8000I5584J13669D01*
G01X393575D01*
Y55118D01*
G02X405512Y67055I11937J0D01*
G01X408351D01*
Y62059D01*
X405512D01*
G03X398571Y55118I0J-6941D01*
G01Y3937D01*
G02X397638Y3004I-933J0D01*
G01X3937D01*
G37*
G36*
G01X8000Y34568D02*
G03X3714Y30984I7158J-12914D01*
G02X3004Y31236I-310J253D01*
G01Y461899D01*
G02X3678Y462191I400J0D01*
G03X8000Y459248I11482J12217D01*
G01Y34568D01*
G37*
G36*
G01X758787Y1460504D02*
Y1378740D01*
G02X746850Y1366803I-11937J0D01*
G01X8000D01*
Y489570D01*
G03X3678Y486627I7160J-15160D01*
G02X3004Y486919I-274J292D01*
G01Y1370866D01*
G02X3937Y1371799I933J0D01*
G01X746850D01*
G03X753791Y1378740I0J6941D01*
G01Y1464567D01*
G02X754724Y1465500I933J0D01*
G01X783465D01*
G03X790406Y1472441I0J6941D01*
G01Y1654331D01*
G02X791339Y1655264I933J0D01*
G01X799262D01*
Y1650268D01*
X795402D01*
Y1472441D01*
G02X795364Y1471483I-11937J-6D01*
G03X794552Y1469561I1484J-1759D01*
G01X794558Y1469470D01*
X794378Y1469290D01*
Y1467605D01*
G02X783465Y1460504I-10914J4836D01*
G01X758787D01*
G37*
G36*
G01X598551Y8000D02*
X783465D01*
G02X794689Y126I0J-11937D01*
G01X796727D01*
Y-4870D01*
X791339D01*
G02X790406Y-3937I0J933D01*
G03X783465Y3004I-6941J0D01*
G01X594488D01*
G02X593555Y3937I0J933D01*
G01Y55118D01*
G03X586614Y62059I-6941J0D01*
G01X585511D01*
Y67055D01*
X586614D01*
G02X598551Y55118I0J-11937D01*
G01Y8000D01*
G37*
G36*
G01X870079Y-149752D02*
G02X869146Y-148819I0J933D01*
G01Y-16366D01*
X873916D01*
Y-79976D01*
X874142Y-80202D01*
Y-144756D01*
X1173102D01*
Y-10706D01*
X1178098D01*
Y-148819D01*
G02X1177165Y-149752I-933J0D01*
G01X870079D01*
G37*
G36*
G01X1003661Y1450910D02*
X994483Y1460088D01*
Y1484620D01*
X995433Y1485570D01*
X1079980D01*
X1082000Y1487590D01*
Y1609593D01*
X1086719Y1614312D01*
X1137982D01*
X1145983Y1606311D01*
Y1459747D01*
X1140726Y1454490D01*
X1140720D01*
X1137140Y1450910D01*
X1003661D01*
G37*
G36*
G01X1078460Y1536040D02*
X1080573Y1533927D01*
Y1492573D01*
X1080550Y1492550D01*
Y1488400D01*
X1079620Y1487470D01*
X995998D01*
X994302Y1489166D01*
Y1534567D01*
X995775Y1536040D01*
X1078460D01*
G37*
G36*
G01X1567055Y55118D02*
Y8000D01*
X1889065D01*
G03X1900305I5620J13654D01*
G01X1926843D01*
Y1366803D01*
X1168110D01*
G02X1156173Y1378740I0J11937D01*
G01Y1468504D01*
G02X1168110Y1480441I11937J0D01*
G01X1212472D01*
Y1650268D01*
X1071589D01*
Y1655264D01*
X1216535D01*
G02X1217468Y1654331I0J-933D01*
G01Y1476378D01*
G02X1216535Y1475445I-933J0D01*
G01X1168110D01*
G03X1161169Y1468504I0J-6941D01*
G01Y1378740D01*
G03X1168110Y1371799I6941J0D01*
G01X1930906D01*
G02X1931839Y1370866I0J-933D01*
G01Y3937D01*
G02X1930906Y3004I-933J0D01*
G01X1562992D01*
G02X1562059Y3937I0J933D01*
G01Y55118D01*
G03X1555118Y62059I-6941J0D01*
G01X1554061D01*
Y67055D01*
X1555118D01*
G02X1567055Y55118I0J-11937D01*
G37*
G36*
G01X1367075Y3937D02*
G02X1366142Y3004I-933J0D01*
G01X1185039D01*
G03X1178098Y-3937I0J-6941D01*
G01Y-9458D01*
X1173102D01*
Y-3937D01*
G02X1185039Y8000I11937J0D01*
G01X1362079D01*
Y55118D01*
G02X1374016Y67055I11937J0D01*
G01X1376944D01*
Y62059D01*
X1374016D01*
G03X1367075Y55118I0J-6941D01*
G01Y3937D01*
G37*
%LPC*%
G75*
G36*
G01X1123366Y1586608D02*
G03X1122697I-334J-220D01*
G02Y1590558I-3012J1975D01*
G03X1123366I335J220D01*
G02Y1586608I3012J-1975D01*
G37*
G36*
G01X1105138D02*
G03X1104469I-334J-220D01*
G02Y1590558I-3012J1975D01*
G03X1105138I334J220D01*
G02Y1586608I3012J-1975D01*
G37*
G36*
G01X1095005Y1553378D02*
G03X1094469I-268J-297D01*
G02X1091290Y1556706I-1543J1708D01*
G03Y1557268I-284J281D01*
G02X1094469Y1560596I1636J1620D01*
G03X1095005I268J297D01*
G02X1098184Y1557268I1543J-1708D01*
G03Y1556706I284J-281D01*
G02X1095005Y1553378I-1636J-1620D01*
G37*
G36*
G01X1097575Y1533801D02*
G03Y1533239I284J-281D01*
G02X1094301I-1637J-1619D01*
G03Y1533801I-284J281D01*
G02X1097575I1637J1619D01*
G37*
G36*
G01X1092455D02*
G03Y1533239I284J-281D01*
G02X1089181I-1637J-1619D01*
G03Y1533801I-284J281D01*
G02X1092455I1637J1619D01*
G37*
G36*
G01X1075050Y1453527D02*
G03X1074458I-296J-269D01*
G02Y1456623I-1704J1548D01*
G03X1075050I296J269D01*
G02Y1453527I1704J-1548D01*
G37*
G36*
G01X1046358Y1456623D02*
G03X1046950I296J269D01*
G02Y1453527I1704J-1548D01*
G03X1046358I-296J-269D01*
G02Y1456623I-1704J1548D01*
G37*
G36*
G01X1018558D02*
G03X1019150I296J269D01*
G02Y1453527I1704J-1548D01*
G03X1018558I-296J-269D01*
G02Y1456623I-1704J1548D01*
G37*
%LPD*%
G75*
G54D10*
X24508Y5500D03*
X5500Y61492D03*
Y56492D03*
Y51492D03*
Y46492D03*
Y41492D03*
Y66492D03*
Y81492D03*
Y76492D03*
Y96492D03*
Y91492D03*
Y86492D03*
Y71492D03*
Y101492D03*
Y111492D03*
Y116492D03*
Y106492D03*
Y126492D03*
Y121492D03*
Y141492D03*
Y151492D03*
Y161492D03*
Y156492D03*
Y146492D03*
Y131492D03*
Y136492D03*
Y181492D03*
Y191492D03*
Y201492D03*
Y211492D03*
Y171492D03*
Y206492D03*
Y196492D03*
Y176492D03*
Y166492D03*
Y186492D03*
Y231492D03*
Y241492D03*
Y251492D03*
Y261492D03*
Y221492D03*
Y256492D03*
Y246492D03*
Y226492D03*
Y216492D03*
Y236492D03*
Y281492D03*
Y291492D03*
Y301492D03*
Y271492D03*
Y306492D03*
Y296492D03*
Y286492D03*
Y276492D03*
Y266492D03*
Y331492D03*
Y341492D03*
Y351492D03*
Y311492D03*
Y321492D03*
Y356492D03*
Y346492D03*
Y336492D03*
Y326492D03*
Y316492D03*
Y381492D03*
Y391492D03*
Y401492D03*
Y361492D03*
Y371492D03*
Y406492D03*
Y396492D03*
Y386492D03*
Y376492D03*
Y366492D03*
Y451492D03*
Y441492D03*
Y431492D03*
Y421492D03*
Y411492D03*
Y416492D03*
Y436492D03*
Y446492D03*
Y426492D03*
Y501492D03*
Y456492D03*
Y496492D03*
Y531492D03*
Y551492D03*
Y541492D03*
Y521492D03*
Y511492D03*
Y536492D03*
Y546492D03*
Y506492D03*
Y516492D03*
Y526492D03*
Y581492D03*
Y591492D03*
Y571492D03*
Y561492D03*
Y586492D03*
Y596492D03*
Y556492D03*
Y566492D03*
Y576492D03*
Y631492D03*
Y641492D03*
Y621492D03*
Y611492D03*
Y601492D03*
Y636492D03*
Y646492D03*
Y606492D03*
Y616492D03*
Y626492D03*
Y681492D03*
Y691492D03*
Y671492D03*
Y661492D03*
Y651492D03*
Y686492D03*
Y696492D03*
Y656492D03*
Y666492D03*
Y676492D03*
Y731492D03*
Y741492D03*
Y721492D03*
Y711492D03*
Y701492D03*
Y736492D03*
Y706492D03*
Y716492D03*
Y726492D03*
Y781492D03*
Y791492D03*
Y771492D03*
Y761492D03*
Y751492D03*
Y786492D03*
Y746492D03*
Y756492D03*
Y766492D03*
Y776492D03*
Y831492D03*
Y841492D03*
Y821492D03*
Y811492D03*
Y801492D03*
Y836492D03*
Y796492D03*
Y806492D03*
Y816492D03*
Y826492D03*
Y881492D03*
Y871492D03*
Y861492D03*
Y851492D03*
Y886492D03*
Y846492D03*
Y856492D03*
Y866492D03*
Y876492D03*
Y931492D03*
Y921492D03*
Y911492D03*
Y901492D03*
Y891492D03*
Y936492D03*
Y896492D03*
Y906492D03*
Y916492D03*
Y926492D03*
Y976492D03*
Y981492D03*
Y986492D03*
Y966492D03*
Y956492D03*
Y961492D03*
Y971492D03*
Y951492D03*
Y941492D03*
Y946492D03*
Y991492D03*
Y996492D03*
Y1001492D03*
Y1006492D03*
Y1026492D03*
Y1016492D03*
Y1011492D03*
Y1021492D03*
Y1031492D03*
Y1036492D03*
Y1066492D03*
Y1056492D03*
Y1046492D03*
Y1041492D03*
Y1051492D03*
Y1061492D03*
Y1071492D03*
Y1081492D03*
Y1076492D03*
Y1121492D03*
Y1131492D03*
Y1111492D03*
Y1101492D03*
Y1091492D03*
Y1086492D03*
Y1096492D03*
Y1106492D03*
Y1116492D03*
Y1126492D03*
Y1171492D03*
Y1161492D03*
Y1151492D03*
Y1141492D03*
Y1136492D03*
Y1146492D03*
Y1156492D03*
Y1166492D03*
Y1176492D03*
Y1221492D03*
Y1211492D03*
Y1201492D03*
Y1191492D03*
Y1181492D03*
Y1186492D03*
Y1196492D03*
Y1206492D03*
Y1216492D03*
Y1226492D03*
Y1271492D03*
Y1261492D03*
Y1251492D03*
Y1241492D03*
Y1231492D03*
Y1236492D03*
Y1246492D03*
Y1256492D03*
Y1266492D03*
Y1276492D03*
Y1321492D03*
Y1311492D03*
Y1301492D03*
Y1291492D03*
Y1281492D03*
Y1286492D03*
Y1296492D03*
Y1306492D03*
Y1316492D03*
X8983Y1368303D03*
X13983D03*
X18983D03*
X23983D03*
X5500Y1361492D03*
Y1351492D03*
Y1341492D03*
Y1331492D03*
Y1336492D03*
Y1346492D03*
Y1356492D03*
Y1326492D03*
X29508Y5500D03*
X39508D03*
X34508D03*
X44508D03*
X64508D03*
X69508D03*
X54508D03*
X49508D03*
X59508D03*
X28983Y1368303D03*
X33983D03*
X38983D03*
X43983D03*
X48983D03*
X53983D03*
X58983D03*
X63983D03*
X68983D03*
X114508Y5500D03*
X119508D03*
X104508D03*
X94508D03*
X84508D03*
X74508D03*
X79508D03*
X89508D03*
X99508D03*
X109508D03*
X73983Y1368303D03*
X78983D03*
X83983D03*
X88983D03*
X93983D03*
X98983D03*
X107374Y1369303D03*
X112374D03*
X117374D03*
X134508Y5500D03*
X124508D03*
X129508D03*
X169508D03*
X159508D03*
X149508D03*
X139508D03*
X154508D03*
X164508D03*
X144508D03*
X122374Y1369303D03*
X127374D03*
X132374D03*
X137374D03*
X142374D03*
X147374D03*
X152374D03*
X157374D03*
X162374D03*
X167374D03*
X209508Y5500D03*
X199508D03*
X189508D03*
X179508D03*
X204508D03*
X214508D03*
X174508D03*
X184508D03*
X194508D03*
X172374Y1369303D03*
X177374D03*
X182374D03*
X187374D03*
X192374D03*
X197374D03*
X202374D03*
X207374D03*
X212374D03*
X217374D03*
X259508Y5500D03*
X249508D03*
X239508D03*
X229508D03*
X219508D03*
X224508D03*
X234508D03*
X244508D03*
X254508D03*
X264508D03*
X222374Y1369303D03*
X227374D03*
X232374D03*
X237374D03*
X242374D03*
X247374D03*
X252374D03*
X257374D03*
X262374D03*
X309508Y5500D03*
X299508D03*
X289508D03*
X279508D03*
X269508D03*
X304508D03*
X314508D03*
X274508D03*
X284508D03*
X294508D03*
X267374Y1369303D03*
X272374D03*
X277374D03*
X282374D03*
X287374D03*
X292374D03*
X297374D03*
X302374D03*
X307374D03*
X312374D03*
X359508Y5500D03*
X349508D03*
X339508D03*
X329508D03*
X319508D03*
X324508D03*
X334508D03*
X344508D03*
X354508D03*
X333983Y1368303D03*
X338983D03*
X343983D03*
X348983D03*
X353983D03*
X358983D03*
X363983D03*
X317374Y1369303D03*
X322374D03*
X327374D03*
X395075Y18639D03*
Y13639D03*
X389508Y5500D03*
X379508D03*
X369508D03*
X364508D03*
X374508D03*
X384508D03*
X394508D03*
X395075Y43639D03*
Y38639D03*
Y33639D03*
Y28639D03*
Y23639D03*
X399000Y62000D03*
X396000Y55500D03*
X396075Y50248D03*
X368983Y1368303D03*
X373983D03*
X378983D03*
X383983D03*
X388983D03*
X393983D03*
X398983D03*
X403983D03*
X408983D03*
X413983D03*
X418983D03*
X423983D03*
X428983D03*
X433983D03*
X438983D03*
X443983D03*
X448983D03*
X453983D03*
X458983D03*
X463983D03*
X468983D03*
X473983D03*
X478983D03*
X483983D03*
X488983D03*
X493983D03*
X498983D03*
X503983D03*
X508983D03*
X517374Y1369303D03*
X522374D03*
X527374D03*
X532374D03*
X537374D03*
X542374D03*
X547374D03*
X552374D03*
X557374D03*
X597051Y7699D03*
Y12699D03*
Y17699D03*
X604146Y5500D03*
X597051Y22699D03*
Y27699D03*
Y32699D03*
Y37699D03*
Y42699D03*
X589000Y64000D03*
X594000Y61500D03*
X596000Y56500D03*
X596051Y51090D03*
X567374Y1369303D03*
X572374D03*
X577374D03*
X582374D03*
X587374D03*
X592374D03*
X597374D03*
X602374D03*
X562374D03*
X609146Y5500D03*
X619146D03*
X614146D03*
X629146D03*
X639146D03*
X649146D03*
X654146D03*
X644146D03*
X634146D03*
X624146D03*
X617374Y1369303D03*
X622374D03*
X627374D03*
X632374D03*
X637374D03*
X642374D03*
X647374D03*
X652374D03*
X607374D03*
X612374D03*
X679146Y5500D03*
X689146D03*
X694146D03*
X684146D03*
X659146D03*
X669146D03*
X664146D03*
X674146D03*
X699146D03*
X667374Y1369303D03*
X672374D03*
X677374D03*
X682374D03*
X687374D03*
X692374D03*
X697374D03*
X702374D03*
X657374D03*
X662374D03*
X749146Y5500D03*
X709146D03*
X719146D03*
X729146D03*
X739146D03*
X744146D03*
X734146D03*
X724146D03*
X714146D03*
X704146D03*
X747374Y1369303D03*
X742374D03*
X717374D03*
X722374D03*
X727374D03*
X732374D03*
X737374D03*
X707374D03*
X712374D03*
X795969Y-1374D03*
X759146Y5500D03*
X769146D03*
X774146D03*
X764146D03*
X754146D03*
X779146D03*
X755500Y1374500D03*
X752500Y1370500D03*
X757287Y1380873D03*
Y1385873D03*
Y1390873D03*
Y1395873D03*
Y1400873D03*
Y1405873D03*
Y1410873D03*
Y1415873D03*
Y1420873D03*
Y1425873D03*
Y1430873D03*
Y1435873D03*
Y1440873D03*
Y1445873D03*
X766156Y1462004D03*
X771156D03*
X790500Y1466500D03*
X786000Y1463500D03*
X756287Y1459264D03*
Y1454264D03*
X779547Y1463004D03*
X792902Y1477964D03*
Y1487964D03*
Y1497964D03*
Y1507964D03*
Y1517964D03*
Y1512964D03*
Y1472964D03*
Y1482964D03*
Y1492964D03*
Y1502964D03*
Y1562964D03*
Y1527964D03*
Y1537964D03*
Y1547964D03*
Y1557964D03*
Y1567964D03*
Y1522964D03*
Y1532964D03*
Y1542964D03*
Y1552964D03*
Y1612964D03*
Y1602964D03*
Y1592964D03*
Y1582964D03*
Y1572964D03*
Y1577964D03*
Y1587964D03*
Y1597964D03*
Y1607964D03*
X797902Y1652964D03*
X792902D03*
Y1642964D03*
Y1632964D03*
Y1622964D03*
Y1627964D03*
Y1637964D03*
Y1647964D03*
Y1617964D03*
X872642Y-140575D03*
Y-135575D03*
Y-130575D03*
Y-125575D03*
X890264Y-147256D03*
X880264D03*
X875264D03*
X885264D03*
X895264D03*
X872642Y-80575D03*
Y-120575D03*
Y-115575D03*
Y-110575D03*
Y-105575D03*
Y-100575D03*
Y-95575D03*
Y-90575D03*
Y-85575D03*
Y-30575D03*
Y-35575D03*
Y-40575D03*
Y-45575D03*
Y-50575D03*
Y-55575D03*
Y-60575D03*
Y-65575D03*
Y-70575D03*
Y-75575D03*
Y-20575D03*
Y-25575D03*
X940264Y-147256D03*
X930264D03*
X925264D03*
X935264D03*
X920264D03*
X910264D03*
X900264D03*
X905264D03*
X915264D03*
X960264D03*
X950264D03*
X955264D03*
X965264D03*
X945264D03*
X990264D03*
X980264D03*
X970264D03*
X975264D03*
X985264D03*
X1010264D03*
X1000264D03*
X1005264D03*
X1015264D03*
X995264D03*
X1040264D03*
X1030264D03*
X1020264D03*
X1025264D03*
X1035264D03*
X1060264D03*
X1050264D03*
X1055264D03*
X1065264D03*
X1045264D03*
X1080264D03*
X1070264D03*
X1075264D03*
X1085264D03*
X1078098Y1652768D03*
X1073098D03*
X1083098D03*
X1088098D03*
X1110264Y-147256D03*
X1100264D03*
X1090264D03*
X1105264D03*
X1095264D03*
X1130264D03*
X1120264D03*
X1115264D03*
X1125264D03*
X1135264D03*
X1093098Y1652768D03*
X1133098D03*
X1123098D03*
X1113098D03*
X1103098D03*
X1108098D03*
X1118098D03*
X1128098D03*
X1098098D03*
X1170264Y-147256D03*
X1155264D03*
X1175602Y-137594D03*
Y-127594D03*
X1160264Y-147256D03*
X1150264D03*
X1140264D03*
X1145264D03*
X1175602Y-132594D03*
Y-142594D03*
X1165264Y-147256D03*
X1175602Y-117594D03*
Y-107594D03*
Y-97594D03*
Y-87594D03*
Y-77594D03*
Y-82594D03*
Y-92594D03*
Y-102594D03*
Y-112594D03*
Y-122594D03*
Y-67594D03*
Y-57594D03*
Y-47594D03*
Y-37594D03*
Y-32594D03*
Y-42594D03*
Y-52594D03*
Y-62594D03*
Y-72594D03*
Y-17594D03*
Y-27594D03*
X1180500Y4000D03*
X1176500Y-500D03*
X1175602Y-22594D03*
Y-12594D03*
Y-7594D03*
X1162000Y1371500D03*
X1169783Y1369303D03*
X1179783D03*
X1174783D03*
X1184783D03*
X1158673Y1417067D03*
Y1407067D03*
Y1397067D03*
Y1387067D03*
Y1377067D03*
Y1412067D03*
Y1402067D03*
Y1392067D03*
Y1382067D03*
Y1422067D03*
Y1442067D03*
Y1452067D03*
X1158500Y1468500D03*
X1158673Y1457067D03*
Y1447067D03*
Y1437067D03*
Y1427067D03*
Y1462067D03*
Y1432067D03*
X1161000Y1474500D03*
X1166673Y1477941D03*
X1171673D03*
X1181673D03*
X1176673D03*
X1143098Y1652768D03*
X1183098D03*
X1173098D03*
X1163098D03*
X1153098D03*
X1158098D03*
X1168098D03*
X1178098D03*
X1138098D03*
X1148098D03*
X1191382Y5500D03*
X1196382D03*
X1186382D03*
X1201382D03*
X1211382D03*
X1221382D03*
X1231382D03*
X1226382D03*
X1216382D03*
X1206382D03*
X1199783Y1369303D03*
X1209783D03*
X1219783D03*
X1229783D03*
X1189783D03*
X1224783D03*
X1214783D03*
X1204783D03*
X1194783D03*
X1191673Y1477941D03*
X1201673D03*
X1214972Y1482642D03*
Y1517642D03*
Y1487642D03*
Y1497642D03*
Y1507642D03*
Y1512642D03*
Y1502642D03*
Y1492642D03*
X1206673Y1477941D03*
X1196673D03*
X1186673D03*
X1211673D03*
X1214972Y1567642D03*
Y1527642D03*
Y1537642D03*
Y1547642D03*
Y1557642D03*
Y1562642D03*
Y1552642D03*
Y1542642D03*
Y1532642D03*
Y1522642D03*
Y1577642D03*
Y1587642D03*
Y1597642D03*
Y1607642D03*
Y1612642D03*
Y1602642D03*
Y1592642D03*
Y1582642D03*
Y1572642D03*
Y1617642D03*
Y1627642D03*
Y1637642D03*
X1213098Y1652768D03*
X1193098D03*
X1203098D03*
X1208098D03*
X1214972Y1642642D03*
Y1632642D03*
X1188098Y1652768D03*
X1198098D03*
X1214972Y1622642D03*
Y1647642D03*
X1251382Y5500D03*
X1261382D03*
X1271382D03*
X1281382D03*
X1276382D03*
X1266382D03*
X1256382D03*
X1241382D03*
X1246382D03*
X1236382D03*
X1249783Y1369303D03*
X1259783D03*
X1269783D03*
X1279783D03*
X1239783D03*
X1274783D03*
X1264783D03*
X1254783D03*
X1234783D03*
X1244783D03*
X1301382Y5500D03*
X1311382D03*
X1296382D03*
X1316382D03*
X1306382D03*
X1291382D03*
X1286382D03*
X1326382D03*
X1321382D03*
X1299783Y1369303D03*
X1309783D03*
X1319783D03*
X1329783D03*
X1289783D03*
X1324783D03*
X1314783D03*
X1304783D03*
X1294783D03*
X1284783D03*
X1363579Y19821D03*
Y14821D03*
Y9821D03*
X1351382Y5500D03*
X1356382D03*
X1346382D03*
X1336382D03*
X1341382D03*
X1331382D03*
X1363579Y44821D03*
Y39821D03*
Y34821D03*
Y29821D03*
Y24821D03*
X1374000Y64500D03*
X1363579Y51618D03*
X1349783Y1369303D03*
X1359783D03*
X1369783D03*
X1339783D03*
X1374783D03*
X1364783D03*
X1354783D03*
X1344783D03*
X1334783D03*
X1399783D03*
X1409783D03*
X1419783D03*
X1379783D03*
X1389783D03*
X1404783D03*
X1414783D03*
X1424783D03*
X1394783D03*
X1384783D03*
X1449783D03*
X1459783D03*
X1469783D03*
X1429783D03*
X1439783D03*
X1444783D03*
X1454783D03*
X1464783D03*
X1474783D03*
X1434783D03*
X1499783D03*
X1509783D03*
X1519783D03*
X1479783D03*
X1489783D03*
X1494783D03*
X1484783D03*
X1504783D03*
X1514783D03*
X1565555Y16517D03*
X1568030Y5500D03*
X1565555Y21517D03*
Y26517D03*
Y31517D03*
Y36517D03*
Y41517D03*
X1557000Y64500D03*
X1561500Y62000D03*
X1564000Y57500D03*
X1564555Y52124D03*
X1549783Y1369303D03*
X1559783D03*
X1569783D03*
X1529783D03*
X1539783D03*
X1524783D03*
X1534783D03*
X1544783D03*
X1554783D03*
X1564783D03*
X1603030Y5500D03*
X1613030D03*
X1573030D03*
X1583030D03*
X1593030D03*
X1618030D03*
X1608030D03*
X1598030D03*
X1588030D03*
X1578030D03*
X1614783Y1369303D03*
X1604783D03*
X1599783D03*
X1609783D03*
X1619783D03*
X1579783D03*
X1589783D03*
X1574783D03*
X1584783D03*
X1594783D03*
X1653030Y5500D03*
X1663030D03*
X1623030D03*
X1633030D03*
X1643030D03*
X1668030D03*
X1658030D03*
X1648030D03*
X1638030D03*
X1628030D03*
X1664783Y1369303D03*
X1654783D03*
X1644783D03*
X1634783D03*
X1624783D03*
X1649783D03*
X1659783D03*
X1629783D03*
X1639783D03*
X1703030Y5500D03*
X1713030D03*
X1673030D03*
X1683030D03*
X1693030D03*
X1718030D03*
X1708030D03*
X1698030D03*
X1688030D03*
X1678030D03*
X1714783Y1369303D03*
X1704783D03*
X1694783D03*
X1684783D03*
X1674783D03*
X1699783D03*
X1709783D03*
X1669783D03*
X1679783D03*
X1689783D03*
X1753030Y5500D03*
X1763030D03*
X1723030D03*
X1733030D03*
X1743030D03*
X1758030D03*
X1748030D03*
X1738030D03*
X1728030D03*
X1764783Y1369303D03*
X1754783D03*
X1744783D03*
X1734783D03*
X1724783D03*
X1749783D03*
X1759783D03*
X1719783D03*
X1729783D03*
X1739783D03*
X1778030Y5500D03*
X1793030D03*
X1803030D03*
X1813030D03*
X1808030D03*
X1798030D03*
X1783030D03*
X1788030D03*
X1773030D03*
X1768030D03*
X1804783Y1369303D03*
X1794783D03*
X1784783D03*
X1774783D03*
X1799783D03*
X1809783D03*
X1769783D03*
X1779783D03*
X1789783D03*
X1843030Y5500D03*
X1853030D03*
X1863030D03*
X1838030D03*
X1858030D03*
X1848030D03*
X1823030D03*
X1833030D03*
X1828030D03*
X1818030D03*
X1854783Y1369303D03*
X1844783D03*
X1834783D03*
X1824783D03*
X1814783D03*
X1849783D03*
X1859783D03*
X1819783D03*
X1829783D03*
X1839783D03*
X1878030Y5500D03*
X1883030D03*
X1873030D03*
X1868030D03*
X1909030D03*
X1888030D03*
X1904783Y1369303D03*
X1894783D03*
X1884783D03*
X1874783D03*
X1864783D03*
X1899783D03*
X1909783D03*
X1869783D03*
X1879783D03*
X1889783D03*
X1929343Y16525D03*
Y11525D03*
Y6525D03*
X1914030Y5500D03*
X1919030D03*
X1924030D03*
X1929343Y46525D03*
Y41525D03*
Y36525D03*
Y31525D03*
Y26525D03*
Y21525D03*
Y66525D03*
Y61525D03*
Y56525D03*
Y51525D03*
Y116525D03*
Y111525D03*
Y106525D03*
Y101525D03*
Y96525D03*
Y91525D03*
Y86525D03*
Y81525D03*
Y76525D03*
Y71525D03*
Y121525D03*
Y126525D03*
Y136525D03*
Y146525D03*
Y156525D03*
Y161525D03*
Y151525D03*
Y141525D03*
Y131525D03*
Y176525D03*
Y186525D03*
Y196525D03*
Y206525D03*
Y166525D03*
Y211525D03*
Y201525D03*
Y191525D03*
Y181525D03*
Y171525D03*
Y226525D03*
Y236525D03*
Y246525D03*
Y256525D03*
Y216525D03*
Y261525D03*
Y251525D03*
Y241525D03*
Y231525D03*
Y221525D03*
Y276525D03*
Y286525D03*
Y296525D03*
Y306525D03*
Y266525D03*
Y301525D03*
Y291525D03*
Y281525D03*
Y271525D03*
Y326525D03*
Y336525D03*
Y346525D03*
Y356525D03*
Y316525D03*
Y351525D03*
Y341525D03*
Y331525D03*
Y321525D03*
Y311525D03*
Y376525D03*
Y386525D03*
Y396525D03*
Y406525D03*
Y366525D03*
Y401525D03*
Y391525D03*
Y381525D03*
Y371525D03*
Y361525D03*
Y426525D03*
Y436525D03*
Y446525D03*
Y416525D03*
Y451525D03*
Y441525D03*
Y431525D03*
Y421525D03*
Y411525D03*
Y476525D03*
Y486525D03*
Y496525D03*
Y456525D03*
Y466525D03*
Y501525D03*
Y491525D03*
Y481525D03*
Y471525D03*
Y461525D03*
Y526525D03*
Y536525D03*
Y546525D03*
Y506525D03*
Y516525D03*
Y551525D03*
Y541525D03*
Y531525D03*
Y521525D03*
Y511525D03*
Y576525D03*
Y586525D03*
Y596525D03*
Y556525D03*
Y566525D03*
Y591525D03*
Y581525D03*
Y571525D03*
Y561525D03*
Y626525D03*
Y636525D03*
Y646525D03*
Y606525D03*
Y616525D03*
Y641525D03*
Y631525D03*
Y621525D03*
Y611525D03*
Y601525D03*
Y676525D03*
Y686525D03*
Y696525D03*
Y656525D03*
Y666525D03*
Y691525D03*
Y681525D03*
Y671525D03*
Y661525D03*
Y651525D03*
Y726525D03*
Y736525D03*
Y706525D03*
Y716525D03*
Y741525D03*
Y731525D03*
Y721525D03*
Y711525D03*
Y701525D03*
Y776525D03*
Y786525D03*
Y746525D03*
Y756525D03*
Y766525D03*
Y791525D03*
Y781525D03*
Y771525D03*
Y761525D03*
Y751525D03*
Y826525D03*
Y836525D03*
Y796525D03*
Y806525D03*
Y816525D03*
Y841525D03*
Y831525D03*
Y821525D03*
Y811525D03*
Y801525D03*
Y876525D03*
Y886525D03*
Y846525D03*
Y856525D03*
Y866525D03*
Y881525D03*
Y871525D03*
Y861525D03*
Y851525D03*
Y926525D03*
Y896525D03*
Y906525D03*
Y916525D03*
Y931525D03*
Y921525D03*
Y911525D03*
Y901525D03*
Y891525D03*
Y936525D03*
Y973863D03*
Y978863D03*
Y983863D03*
Y951525D03*
Y956525D03*
Y961525D03*
Y966525D03*
Y946525D03*
Y941525D03*
Y988863D03*
Y993863D03*
Y998863D03*
Y1003863D03*
Y1008863D03*
Y1033863D03*
Y1028863D03*
Y1023863D03*
Y1018863D03*
Y1013863D03*
Y1073863D03*
Y1083863D03*
Y1043863D03*
Y1053863D03*
Y1063863D03*
Y1078863D03*
Y1068863D03*
Y1058863D03*
Y1048863D03*
Y1038863D03*
Y1123863D03*
Y1093863D03*
Y1103863D03*
Y1113863D03*
Y1128863D03*
Y1118863D03*
Y1108863D03*
Y1098863D03*
Y1088863D03*
Y1173863D03*
Y1133863D03*
Y1143863D03*
Y1153863D03*
Y1163863D03*
Y1178863D03*
Y1168863D03*
Y1158863D03*
Y1148863D03*
Y1138863D03*
Y1223863D03*
Y1183863D03*
Y1193863D03*
Y1203863D03*
Y1213863D03*
Y1228863D03*
Y1218863D03*
Y1208863D03*
Y1198863D03*
Y1188863D03*
Y1273863D03*
Y1233863D03*
Y1243863D03*
Y1253863D03*
Y1263863D03*
Y1268863D03*
Y1258863D03*
Y1248863D03*
Y1238863D03*
Y1323863D03*
Y1283863D03*
Y1293863D03*
Y1303863D03*
Y1313863D03*
Y1318863D03*
Y1308863D03*
Y1298863D03*
Y1288863D03*
Y1278863D03*
Y1333863D03*
Y1343863D03*
Y1353863D03*
X1924783Y1369303D03*
X1914783D03*
X1919783D03*
X1929343Y1358863D03*
Y1348863D03*
Y1338863D03*
Y1328863D03*
Y1363863D03*
G54D11*
X19712Y1176350D03*
X47607Y527511D03*
X61834Y527515D03*
X27143Y663071D03*
X27510Y688422D03*
X39325Y1131400D03*
X26723Y1116038D03*
X36848Y1173600D03*
X27090Y1141389D03*
X31500Y1224000D03*
X39425Y1226200D03*
X37225Y1230100D03*
X45518Y1336366D03*
X41381Y1335567D03*
X95437Y176661D03*
X85146Y621637D03*
X95537Y1082173D03*
X145437Y265561D03*
X150253Y709713D03*
X145437Y717617D03*
X140364Y749807D03*
X148400Y1086900D03*
X145437Y1165673D03*
X150862Y1152723D03*
X148300Y1228800D03*
X148311Y1182767D03*
X163500Y1345200D03*
X171861Y527469D03*
X186088Y527473D03*
X199900Y923200D03*
X195100Y1096800D03*
X219749Y176661D03*
Y618917D03*
X258600Y715500D03*
X264731Y749551D03*
X223100Y920600D03*
X239000Y985600D03*
X252100Y990100D03*
X244600Y1004600D03*
X261100Y1005700D03*
X219749Y1082173D03*
X264864Y1120500D03*
X269649Y266261D03*
X291601Y418503D03*
X296032Y527469D03*
X310259Y527473D03*
X274520Y709457D03*
X268100Y982300D03*
X273300Y981700D03*
X280800Y1011900D03*
X281200Y1033000D03*
X271100Y1063200D03*
X281500Y1036744D03*
X269649Y1165673D03*
X275385Y1152596D03*
X315500Y1216700D03*
X276100Y1229100D03*
X273243Y1182915D03*
X286925Y1201945D03*
X295900Y1339700D03*
X296100Y1335100D03*
X279900Y1328300D03*
X283700D03*
X286100Y1349659D03*
X292600Y1337367D03*
X289510Y1342259D03*
X354100Y62100D03*
X345321Y102400D03*
X347881Y114881D03*
X342761Y114861D03*
X350441Y117541D03*
X341114Y123622D03*
X345321Y118921D03*
X344062Y176461D03*
X333682Y621858D03*
X335300Y926900D03*
X337100Y972100D03*
X344737Y995637D03*
X350673Y1031200D03*
X344062Y1082073D03*
X331679Y1175800D03*
X386800Y263800D03*
X393862Y719917D03*
X398677Y709385D03*
X388788Y749479D03*
X408672Y1008038D03*
X388888Y1118173D03*
X393679Y1157480D03*
X383191Y1170203D03*
X398527Y1188659D03*
Y1233336D03*
X441645Y288847D03*
Y284647D03*
X456190Y354105D03*
X452800Y420912D03*
X418600Y445462D03*
X421700Y450200D03*
X447533Y475900D03*
X458679Y470700D03*
X450500Y459562D03*
X420182Y527432D03*
X434409Y527436D03*
X457853Y622091D03*
X435082Y915200D03*
X437600Y917800D03*
X445582Y925352D03*
X449137Y967757D03*
X429613Y1017920D03*
X432657Y1015102D03*
X442600Y998300D03*
X413000Y1054200D03*
X442473Y1068726D03*
X441400Y1169400D03*
X416900Y1221800D03*
X412300Y1326200D03*
X415422Y1352000D03*
X422373Y1359747D03*
X418922Y1356522D03*
X462200Y173109D03*
X468472Y182441D03*
X462133Y473300D03*
X481533Y480875D03*
X497351Y531531D03*
X501023Y534941D03*
X472022Y582062D03*
X465200Y1018200D03*
X506500Y1051900D03*
X505874Y1134773D03*
X509180Y145419D03*
X539584Y184694D03*
X542155Y187543D03*
X515324Y252511D03*
X553742Y267705D03*
X510700Y277200D03*
X534905Y354105D03*
X518700Y548700D03*
X553279Y523331D03*
X514500Y524469D03*
X528727Y524973D03*
X509996Y716996D03*
X522773Y709638D03*
X512884Y749732D03*
X530800Y1028300D03*
X515800Y1028000D03*
X556022Y1042817D03*
X552436Y1042494D03*
X509037Y1136700D03*
X524828Y1159231D03*
X522867Y1190284D03*
Y1231097D03*
X520600Y1324100D03*
X536000Y1359826D03*
X541362D03*
X518397Y1360000D03*
X512900Y1345600D03*
X553587Y1346026D03*
X527000Y1340600D03*
X521500Y1342800D03*
X566271Y167387D03*
X592767Y179277D03*
X598236Y181981D03*
X592387Y629417D03*
X593365Y877358D03*
X592614Y882300D03*
X571400Y1000100D03*
X592387Y1082173D03*
X600640Y1171000D03*
X592400Y1214456D03*
X619171Y112329D03*
X639537Y248011D03*
X642287Y266461D03*
X612000Y502300D03*
X627863Y522000D03*
X642509Y520667D03*
X642287Y719817D03*
X647207Y709555D03*
X637318Y749649D03*
X645200Y1067800D03*
X636803Y1167864D03*
X642942Y1156818D03*
X632603Y1136225D03*
X647716Y1154150D03*
X627632Y1217300D03*
X647126Y1189513D03*
X690807Y103298D03*
X700000Y654417D03*
X658574Y930100D03*
X677457Y944796D03*
X663800Y1018300D03*
X682200Y1026500D03*
X674300Y1001620D03*
X664000Y1278100D03*
X673000Y1354100D03*
X747242Y197553D03*
X717188Y176461D03*
X705348Y478425D03*
X716600Y629417D03*
Y1081973D03*
X710000Y1107173D03*
X728174Y1275611D03*
X725678Y1272799D03*
X722790Y1270557D03*
X720446Y1267427D03*
X731500Y1277811D03*
X757020Y159692D03*
X758619Y168537D03*
X763188Y172500D03*
X789739Y365493D03*
X754500Y668741D03*
X776400Y956500D03*
X780800Y959300D03*
X786800Y1016000D03*
X784000Y1024000D03*
X759500Y1056100D03*
X779535Y1180469D03*
X792263Y1178661D03*
Y1174461D03*
Y1170261D03*
X752500Y1167500D03*
X784544Y1210178D03*
Y1205978D03*
X779535Y1193469D03*
Y1189269D03*
Y1184669D03*
X797177Y1189537D03*
X797225Y1185337D03*
X792263Y1182861D03*
X769728Y1325747D03*
X772900Y1328550D03*
X796848Y1469724D03*
X829921Y-458D03*
X833724Y-3346D03*
X806299Y-458D03*
X814173D03*
X822047D03*
X845661Y-3642D03*
X843463Y530D03*
X806314Y35952D03*
X842470Y41295D03*
X841733Y36654D03*
X803438Y1139700D03*
X806952Y1460496D03*
X806568Y1464275D03*
X802433Y1461619D03*
X800900Y1465234D03*
X800462Y1469231D03*
X834974Y1533243D03*
X886322Y69D03*
X867080Y393D03*
X886427Y3802D03*
X873892Y287D03*
X886418Y-7350D03*
X849484Y649D03*
X886351Y-3735D03*
X857513Y659D03*
X885448Y37380D03*
X872796Y251714D03*
X881549Y326304D03*
X874800Y355798D03*
X874807Y375193D03*
X878500Y476000D03*
X891200Y838200D03*
X894965Y843500D03*
X888962Y843262D03*
X882333Y896320D03*
X863800Y1309876D03*
X873259Y1365805D03*
X873918Y1411149D03*
X863851Y1501681D03*
X860179Y1491170D03*
X876200Y1553900D03*
X876190Y1537187D03*
X876100Y1549000D03*
X876200Y1558400D03*
X892700Y1524700D03*
X942000Y752850D03*
X897000Y839000D03*
X903000Y842500D03*
X896212Y1345788D03*
X895900Y1390100D03*
X896200Y1386000D03*
X896100Y1393800D03*
X896200Y1397900D03*
Y1405300D03*
X896100Y1401600D03*
X923829Y1389012D03*
X906600Y1461600D03*
X909400Y1459200D03*
X910000Y1464900D03*
X905500Y1467161D03*
X908742Y1477427D03*
X908542Y1481127D03*
X922500Y1509700D03*
X897400Y1574000D03*
X897038Y1577600D03*
X924059Y1647700D03*
X981700Y-115500D03*
X976713Y-115570D03*
X989316Y-94984D03*
X992185Y-54411D03*
X989050Y-70850D03*
X977794Y695103D03*
X952200Y742600D03*
X957100Y742900D03*
X977622Y699464D03*
X953200Y736700D03*
X956900Y737600D03*
X949048Y755225D03*
X952476Y753652D03*
X951300Y747900D03*
X956200Y748200D03*
X957320Y769818D03*
X947866Y763541D03*
X957629Y766231D03*
X952820Y769518D03*
X944500Y760750D03*
X987734Y979575D03*
X964537Y1160310D03*
X958870Y1163617D03*
X962941Y1165929D03*
X967497Y1168802D03*
X957871Y1171219D03*
X963000Y1174427D03*
X969463Y1177599D03*
X972924Y1158033D03*
X982387Y1183598D03*
X998045Y-79300D03*
X993816Y-95184D03*
X1000418Y-69982D03*
X993000Y-60600D03*
X1019118Y-34382D03*
X1019082Y-71000D03*
X1026717Y-11646D03*
X1021086Y-11682D03*
X1020250Y357188D03*
X1034271Y876911D03*
X1011100Y904600D03*
X1025000Y897700D03*
X1007849Y1033743D03*
X996600D03*
X1037282Y995028D03*
X1017354Y1196124D03*
X1021061Y1198543D03*
X1025335Y1324216D03*
X1025284Y1341216D03*
X1033000Y1416125D03*
X1028000Y1404700D03*
Y1411000D03*
X1031500Y1408000D03*
X1051713Y-114887D03*
X1056713Y-115413D03*
X1086713Y-115570D03*
X1081713D03*
X1071713D03*
X1066713D03*
X1041713Y-115465D03*
X1079455Y-30742D03*
X1043303Y-27685D03*
X1045873Y-24660D03*
X1043513Y-21696D03*
X1041500Y382858D03*
X1074425Y447225D03*
X1071950Y453288D03*
X1043674Y451921D03*
X1043500Y446600D03*
X1069018Y456900D03*
X1065985Y460500D03*
X1050763Y829163D03*
X1086600Y833200D03*
X1041616Y997225D03*
X1083355Y1116103D03*
X1075600Y1179090D03*
X1053743Y1174221D03*
X1046900Y1168000D03*
X1076032Y1191144D03*
X1070000Y1184100D03*
X1079500Y1276100D03*
X1077300Y1271700D03*
X1042343Y1324216D03*
X1048251Y1349992D03*
X1046372Y1356326D03*
X1042343Y1337616D03*
X1042443Y1342668D03*
X1042343Y1330916D03*
X1089318Y-91682D03*
X1101246Y-31005D03*
X1124024Y-30840D03*
X1128765Y-34297D03*
X1111254Y-31020D03*
X1105328Y-31005D03*
X1094300Y-60300D03*
X1134110Y176500D03*
X1136203Y167600D03*
X1089300Y836100D03*
X1119500Y1125100D03*
X1115000D03*
X1123600Y1096400D03*
X1123838Y1092800D03*
X1123600Y1100000D03*
X1133981Y1096283D03*
X1134002Y1092600D03*
X1134103Y1099881D03*
X1137436Y1124750D03*
X1092200Y1125800D03*
X1146768Y-31238D03*
X1139808Y-31171D03*
X1149699Y-35153D03*
X1142293Y-37522D03*
X1140550Y179200D03*
X1142800Y174637D03*
X1140500Y171400D03*
X1171749Y259163D03*
X1175400Y258800D03*
X1138198Y832424D03*
X1152880Y1097672D03*
X1152682Y1091138D03*
X1149984Y1115804D03*
X1143550Y1120317D03*
X1139524Y1121817D03*
X1150420Y1229800D03*
X1149823Y1233373D03*
X1144000Y1310000D03*
X1215795Y181242D03*
X1215600Y261800D03*
X1219962Y244739D03*
X1193800Y307857D03*
X1198100Y306858D03*
X1226045Y431102D03*
X1232842Y1140722D03*
X1205303Y1227604D03*
X1250016Y247017D03*
X1253300Y227700D03*
X1262075Y297100D03*
X1250500Y266600D03*
X1239362Y524168D03*
X1253511Y517606D03*
X1268400Y716100D03*
X1243200Y933700D03*
X1259808Y927260D03*
X1271296Y986867D03*
X1274413Y984613D03*
X1279599Y976407D03*
X1253338Y980784D03*
X1253975Y970147D03*
X1264269Y981248D03*
X1263618Y990606D03*
X1268378Y990608D03*
X1239900Y1024000D03*
X1256142Y1029316D03*
X1252400Y1054100D03*
X1272755Y1137293D03*
X1260300Y1169000D03*
X1240314Y1139741D03*
X1254800Y1269600D03*
X1240276Y1356700D03*
X1323829Y55929D03*
X1312263Y95463D03*
X1314794Y162944D03*
X1316000Y772200D03*
X1310500Y774700D03*
X1312767Y885535D03*
X1286000Y982200D03*
X1317400Y1068000D03*
X1351200Y68600D03*
X1359350Y66350D03*
X1358355Y81488D03*
X1338215Y107586D03*
X1336034Y82542D03*
X1334383Y75892D03*
X1340961Y78811D03*
X1343521Y85472D03*
X1347607Y101337D03*
X1346081Y80671D03*
X1348641Y83326D03*
X1352351Y101724D03*
X1350779Y106496D03*
X1348641Y110550D03*
X1333281Y85133D03*
X1341922Y105649D03*
X1354500Y75400D03*
X1349931Y138361D03*
X1333988Y161471D03*
X1358971Y129978D03*
X1362685Y130109D03*
X1351665Y128325D03*
X1343112Y128997D03*
X1364017Y123277D03*
X1372274Y272874D03*
X1355991Y275272D03*
X1374338Y292900D03*
X1358573Y290900D03*
X1375700Y413400D03*
X1338100Y520300D03*
X1353500Y518900D03*
X1336000Y627000D03*
X1347600Y734078D03*
X1344062Y737800D03*
X1354500Y747304D03*
X1360920Y749829D03*
X1334300Y771200D03*
X1338729Y776131D03*
X1338700Y771500D03*
X1334329Y775831D03*
X1373519Y761900D03*
X1341219Y933282D03*
X1346080Y907004D03*
X1378100Y972100D03*
X1339404Y969600D03*
X1353762Y969886D03*
X1349829Y1014840D03*
X1365551Y1028250D03*
X1361074Y1114565D03*
X1360238Y1143867D03*
X1355733Y1241900D03*
X1369600Y1330100D03*
X1373700Y1330000D03*
X1365551Y1353500D03*
X1427663Y167032D03*
X1384713Y323200D03*
X1414882Y397271D03*
X1395300Y438500D03*
X1418225Y421700D03*
X1383952Y717435D03*
X1392355Y886696D03*
X1391000Y932400D03*
X1380300Y930200D03*
X1384800Y1002666D03*
X1383899Y1166690D03*
X1388500Y1224900D03*
X1381800Y1329600D03*
X1463804Y138605D03*
X1456373Y168971D03*
X1444238Y349852D03*
X1439654D03*
X1431909Y359311D03*
X1463000Y490638D03*
X1474700Y569100D03*
X1455202Y618557D03*
X1474083Y764750D03*
X1471608Y768500D03*
X1435300Y882700D03*
X1440500Y893500D03*
X1448000Y910000D03*
X1463616Y969265D03*
X1451800Y1004700D03*
X1446213Y1062300D03*
X1467000Y1221800D03*
X1473600Y1242777D03*
X1511177Y125412D03*
X1508925Y323200D03*
X1481938Y489926D03*
X1497849Y545264D03*
X1513200Y519700D03*
X1509800Y516100D03*
X1494400Y560400D03*
Y556100D03*
X1500539Y739639D03*
X1498000Y743000D03*
X1505900Y717600D03*
X1489000Y723000D03*
X1476558Y759088D03*
X1479033Y762259D03*
X1486600Y786559D03*
X1505900Y930400D03*
X1521200Y928000D03*
X1503394Y968179D03*
X1477974Y970044D03*
X1484000Y992315D03*
X1481500Y995758D03*
X1478194Y1017166D03*
X1481529Y1030500D03*
X1485608Y1113628D03*
X1504200Y1171300D03*
X1485833Y1140369D03*
X1491662Y1351300D03*
X1494662Y1336000D03*
X1497200Y1342500D03*
X1501600Y1342300D03*
X1568500Y438500D03*
Y544100D03*
X1568000Y548500D03*
X1526000Y728000D03*
X1570500Y888400D03*
X1570425Y1062000D03*
X1558650Y1217426D03*
X1579371Y166019D03*
X1586596Y518723D03*
X1600745Y517561D03*
X1578926Y618657D03*
X1584800Y895800D03*
X1587400Y912200D03*
X1608200Y914400D03*
X1618200Y916800D03*
X1574576Y976700D03*
X1615494Y973179D03*
X1587829Y969191D03*
X1602187Y969970D03*
X1580381Y1007066D03*
X1602400Y1019366D03*
X1620059Y1032932D03*
Y1128071D03*
X1613400Y1236500D03*
X1622738Y264938D03*
X1621138Y719238D03*
X1643344Y887455D03*
X1646013Y884255D03*
X1639644Y889755D03*
X1633600Y936300D03*
X1621787Y917108D03*
X1636400Y925800D03*
X1629094Y975179D03*
X1624198Y1111309D03*
X1633138Y1165673D03*
X1624500Y1349100D03*
X1703584Y166019D03*
X1711061Y518470D03*
X1705000Y618667D03*
X1692100Y923600D03*
X1704010Y898000D03*
X1674814Y961977D03*
X1677056Y954636D03*
X1680012Y952402D03*
X1680087Y1023983D03*
X1671422Y1009266D03*
X1690279Y1011526D03*
X1691771Y1035163D03*
X1685100Y1054000D03*
X1679300Y1043169D03*
X1694638Y1063600D03*
X1702838Y1215300D03*
X1710617Y1231429D03*
X1715049Y1234000D03*
X1747550Y265000D03*
X1725100Y519300D03*
X1733245Y1115503D03*
X1751400Y1173900D03*
X1732768Y1141697D03*
X1755900Y1212704D03*
X1740000Y1346900D03*
X1813851Y927406D03*
X1788726Y1034726D03*
X1841021Y152968D03*
X1827796Y166019D03*
X1834896Y518597D03*
X1849045Y517435D03*
X1827667Y618703D03*
X1840855Y606200D03*
X1824170Y886349D03*
X1819541Y921500D03*
X1823937Y890883D03*
X1836200Y1130000D03*
X1840585Y1151653D03*
X1842000Y1344700D03*
X1869500Y179134D03*
Y633500D03*
X1887402Y1050193D03*
X1864617Y1040934D03*
X1873500Y1329000D03*
G54D12*
X429724Y116339D03*
Y96654D03*
Y102166D03*
Y110827D03*
X443898Y116339D03*
X436811Y114764D03*
X443898Y96654D03*
X458071Y102166D03*
X450984Y106103D03*
X443898Y110827D03*
X436811Y120276D03*
X450984D03*
X465157Y100591D03*
Y106103D03*
X472244Y96654D03*
Y102166D03*
X479331Y106103D03*
X528937Y116339D03*
Y110827D03*
X521850Y106103D03*
Y100591D03*
X528937Y102166D03*
X543110Y96654D03*
X528937D03*
X557283Y116339D03*
Y110827D03*
Y102166D03*
Y96654D03*
X833859Y1626772D03*
Y1632284D03*
X840945Y1644882D03*
X826772D03*
X840945Y1650394D03*
X826772D03*
X890552Y1602363D03*
Y1607874D03*
Y1612205D03*
X869292Y1616536D03*
X855118D03*
X848032Y1618111D03*
X869292Y1622048D03*
X855118D03*
X890552Y1636221D03*
Y1650394D03*
X897638Y1598425D03*
Y1603937D03*
Y1608268D03*
X904725Y1630709D03*
Y1640551D03*
Y1650394D03*
X1113530Y995678D03*
X1119042D03*
X1115105Y1016938D03*
X1113530Y1024025D03*
X1119042D03*
X1115105Y1174430D03*
X1109593Y1188603D03*
Y1202776D03*
X1113530Y1181516D03*
Y1195690D03*
X1109593Y1287816D03*
Y1301989D03*
X1115105D03*
X1113530Y1280729D03*
Y1294902D03*
Y1309075D03*
Y1323249D03*
X1119042Y1294902D03*
Y1309075D03*
Y1323249D03*
X1109593Y1344508D03*
Y1372855D03*
X1115105Y1344508D03*
Y1372855D03*
X1119042Y1337422D03*
Y1351595D03*
X1109593Y1387028D03*
X1115105D03*
X1113530Y1379942D03*
Y1394115D03*
Y1408288D03*
X1119042Y1379942D03*
Y1394115D03*
X1398228Y116339D03*
Y96654D03*
Y102166D03*
Y110827D03*
X1412402Y116339D03*
X1405315Y114764D03*
X1412402Y96654D03*
X1426575D03*
Y102166D03*
X1419488Y106103D03*
X1412402Y110827D03*
X1405315Y120276D03*
X1419488D03*
X1433661Y100591D03*
Y106103D03*
X1440748Y96654D03*
Y102166D03*
X1433661Y120276D03*
X1483268Y102166D03*
Y96654D03*
X1511614Y116339D03*
X1497441D03*
Y110827D03*
X1518701Y106103D03*
X1490354D03*
X1518701Y100591D03*
X1490354D03*
X1497441Y102166D03*
X1511614Y96654D03*
X1497441D03*
X1525787Y102166D03*
Y96654D03*
G54D13*
X1039845Y1467746D03*
X1026345D03*
X1030845D03*
X1035345D03*
X1039845Y1463246D03*
X1026345D03*
X1030845D03*
X1035345D03*
X1005400Y1463157D03*
X1000900D03*
X996400D03*
X1009900D03*
X1005400Y1467657D03*
X1000900D03*
X996400D03*
X1009900D03*
X1035345Y1476746D03*
X1030845D03*
X1026345D03*
X1039845D03*
Y1472246D03*
X1026345D03*
X1030845D03*
X1035345D03*
X1005400Y1472157D03*
X1000900D03*
X996400D03*
X1009900D03*
Y1476657D03*
X1005400D03*
X1000900D03*
X996400D03*
X1023583Y1489593D03*
X995783D03*
X1000500Y1511400D03*
X1036578Y1511210D03*
X1014690Y1511178D03*
X1010190D03*
X1005690D03*
X1031790Y1511078D03*
X1027290D03*
X1019600Y1511100D03*
X1023583Y1501593D03*
Y1507593D03*
Y1495593D03*
X995783D03*
Y1501593D03*
Y1507593D03*
X1040583Y1517883D03*
X1031799Y1534392D03*
X1031882Y1528985D03*
X1026459Y1528919D03*
X1026376Y1534326D03*
X1014867D03*
X1014950Y1528919D03*
X1020290Y1534392D03*
X1020373Y1528985D03*
X1040500Y1529290D03*
X1040583Y1523883D03*
X1062700Y1463100D03*
X1058200D03*
X1067200D03*
X1062700Y1467600D03*
X1058200D03*
X1067200D03*
X1053700Y1463100D03*
Y1467600D03*
X1062700Y1472100D03*
X1058200D03*
X1067200D03*
Y1476600D03*
X1058200D03*
X1062700D03*
X1053700Y1472100D03*
Y1476600D03*
X1078683Y1489593D03*
X1051383D03*
X1041810Y1511084D03*
X1055310D03*
X1059810D03*
X1064310D03*
X1068810D03*
X1073310D03*
X1078683Y1495593D03*
Y1501593D03*
Y1507593D03*
Y1516593D03*
X1051383Y1495593D03*
Y1501593D03*
Y1507593D03*
X1078683Y1522593D03*
G54D14*
X1101457Y1601181D03*
X1119685D03*
X1108150D03*
X1126378D03*
G54D15*
G01X286925Y1201945D02*
X287912Y1200958D01*
Y1014512D01*
X282100Y1008700D01*
Y759000D01*
X287912Y753188D01*
Y753028D01*
X293605Y747335D01*
Y631563D01*
X311231Y613937D01*
Y557468D01*
X272273Y518510D01*
Y270251D01*
X274326Y268198D01*
Y258291D01*
X272000Y255965D01*
Y216800D01*
X341114Y147686D01*
Y123622D01*
G01X289510Y1342259D02*
X288900Y1341649D01*
Y1203927D01*
X289912Y1202915D01*
Y753857D01*
X295605Y748164D01*
Y632392D01*
X313477Y614520D01*
Y556885D01*
X277659Y521067D01*
Y214871D01*
X277700Y214830D01*
Y214430D01*
X343485Y148645D01*
Y121334D01*
X342761Y120610D01*
Y114861D01*
G01X472022Y582062D02*
Y500221D01*
X487699Y484544D01*
Y348560D01*
X505500Y330759D01*
Y270200D01*
X517530Y258170D01*
Y249937D01*
X509180Y241587D01*
Y145419D01*
G01X543110Y96654D02*
Y96686D01*
X539554Y100242D01*
Y169446D01*
X535654Y173346D01*
Y332728D01*
X514488Y353894D01*
Y487512D01*
X493003Y508997D01*
Y579253D01*
X501523Y587773D01*
Y621757D01*
X533935Y654169D01*
Y681728D01*
X578294Y726087D01*
Y753790D01*
X588152Y763648D01*
Y956046D01*
X564413Y979785D01*
Y1048156D01*
X558761Y1053808D01*
Y1226039D01*
X534836Y1249964D01*
Y1338136D01*
X539600Y1342900D01*
X550461D01*
X553587Y1346026D01*
G01X515800Y1028000D02*
X519100Y1024700D01*
Y929575D01*
X560002Y888673D01*
Y768782D01*
X515551Y724331D01*
Y718024D01*
X509999Y712472D01*
Y710358D01*
X510001Y710356D01*
Y674360D01*
X486280Y650639D01*
Y643370D01*
X472022Y629112D01*
Y582062D01*
G01X515800Y1028000D02*
X512037Y1031763D01*
Y1114900D01*
X518200Y1121063D01*
Y1239800D01*
X515399Y1242601D01*
Y1343101D01*
X512900Y1345600D01*
G01X890552Y1650394D02*
X879321Y1639163D01*
Y1590939D01*
X844090Y1555708D01*
Y1518825D01*
X842442Y1517177D01*
Y1278410D01*
X867601Y1253251D01*
Y860399D01*
X880250Y847750D01*
Y823050D01*
X932900Y770400D01*
X951938D01*
X952820Y769518D01*
G01X890552Y1636221D02*
X881757Y1627426D01*
Y1588899D01*
X846090Y1553232D01*
Y1517996D01*
X844442Y1516348D01*
Y1279239D01*
X869601Y1254080D01*
Y869899D01*
X878250Y861250D01*
Y852579D01*
X882251Y848578D01*
Y846922D01*
X882250Y846921D01*
Y824450D01*
X934200Y772500D01*
X954638D01*
X957320Y769818D01*
G01X890552Y1612205D02*
X884192Y1605845D01*
Y1586595D01*
X850751Y1553154D01*
Y1541528D01*
X848090Y1538867D01*
Y1517167D01*
X846442Y1515519D01*
Y1280068D01*
X871601Y1254909D01*
Y870728D01*
X880250Y862079D01*
Y853408D01*
X884251Y849407D01*
Y846093D01*
X884250Y846092D01*
Y829250D01*
X939000Y774500D01*
X956200D01*
X970500Y760200D01*
Y642827D01*
X991686Y621641D01*
Y542484D01*
X980570Y531368D01*
Y370940D01*
X998724Y352786D01*
Y105917D01*
X997405Y104598D01*
Y42342D01*
X998724Y41023D01*
Y-29875D01*
X992185Y-36414D01*
Y-54411D01*
G01X876200Y1553900D02*
X871900Y1549600D01*
Y1499391D01*
X880600Y1490691D01*
Y1483758D01*
X882505Y1481853D01*
Y1447086D01*
X891257Y1438334D01*
Y1417192D01*
X880026Y1405961D01*
Y1274015D01*
X889416Y1264625D01*
Y985020D01*
X889261Y984865D01*
Y881650D01*
X977622Y793289D01*
Y699464D01*
G01X977794Y695103D02*
X979822Y697131D01*
Y793678D01*
X979623Y793877D01*
Y794117D01*
X891261Y882479D01*
Y984036D01*
X891416Y984191D01*
Y1265454D01*
X882361Y1274509D01*
Y1373861D01*
X884426Y1375926D01*
Y1407532D01*
X893257Y1416363D01*
Y1439594D01*
X884505Y1448346D01*
Y1482682D01*
X882600Y1484587D01*
Y1520070D01*
X873900Y1528770D01*
Y1546800D01*
X876100Y1549000D01*
G01X876200Y1558400D02*
X869900Y1552100D01*
Y1497861D01*
X876385Y1491376D01*
Y1485144D01*
X880505Y1481024D01*
Y1446257D01*
X889257Y1437505D01*
Y1418021D01*
X876311Y1405075D01*
Y1274900D01*
X886861Y1264350D01*
Y1264349D01*
X887261Y1263949D01*
Y879539D01*
X899676Y867124D01*
Y845824D01*
X903000Y842500D01*
G01X892700Y1524700D02*
X886600Y1518600D01*
Y1486245D01*
X888505Y1484340D01*
Y1450004D01*
X897257Y1441252D01*
Y1412351D01*
X891700Y1406794D01*
Y1355276D01*
X901024Y1345952D01*
Y1273799D01*
X893416Y1266191D01*
Y985020D01*
X893461Y984975D01*
Y886039D01*
X983429Y796071D01*
Y638230D01*
X997162Y624497D01*
Y539682D01*
X986601Y529121D01*
Y372655D01*
X1005064Y354192D01*
Y104511D01*
X1002881Y102328D01*
Y44612D01*
X1006645Y40848D01*
Y-29700D01*
X999277Y-37068D01*
Y-54378D01*
X993000Y-60655D01*
Y-60600D01*
G01X876190Y1537187D02*
Y1529672D01*
X884700Y1521162D01*
Y1519529D01*
X884600Y1519429D01*
Y1485416D01*
X886505Y1483511D01*
Y1449175D01*
X895257Y1440423D01*
Y1413180D01*
X889700Y1407623D01*
Y1352300D01*
X896212Y1345788D01*
G01X923829Y1389012D02*
X927457Y1392640D01*
Y1468686D01*
X916300Y1479843D01*
Y1501600D01*
X922500Y1507800D01*
Y1509700D01*
G01X1343112Y128997D02*
Y146188D01*
X1337040Y152260D01*
Y296368D01*
X1343136Y302464D01*
Y417219D01*
X1285137Y475218D01*
Y580636D01*
X1273206Y592567D01*
Y673203D01*
X1277221Y677218D01*
Y701121D01*
X1310500Y734400D01*
Y774700D01*
G01X1341922Y105649D02*
Y112760D01*
X1345312Y116150D01*
Y147115D01*
X1339414Y153013D01*
Y295913D01*
X1345136Y301635D01*
Y418048D01*
X1287137Y476047D01*
Y581465D01*
X1282636Y585966D01*
Y598007D01*
X1287043Y602414D01*
Y620496D01*
X1275206Y632333D01*
Y672374D01*
X1279221Y676389D01*
Y689621D01*
X1316000Y726400D01*
Y772200D01*
G01X1358971Y129978D02*
X1358857Y129864D01*
Y93497D01*
X1351379Y86019D01*
Y82191D01*
X1351200Y82012D01*
Y68600D01*
G01X1354500Y75400D02*
Y84802D01*
X1361020Y91322D01*
Y124153D01*
X1362685Y125818D01*
Y130109D01*
G01X1497849Y545264D02*
Y537849D01*
X1478946Y518946D01*
Y512589D01*
X1450013Y483656D01*
Y187275D01*
X1448513Y185775D01*
Y160183D01*
X1460896Y147800D01*
Y141513D01*
X1463804Y138605D01*
G01X1511614Y96654D02*
Y96686D01*
X1507700Y100600D01*
Y130100D01*
X1487899Y149901D01*
Y456246D01*
X1539997Y508344D01*
Y565624D01*
X1486721Y618900D01*
Y786438D01*
X1486600Y786559D01*
G01X1511614Y116339D02*
X1514114Y118839D01*
Y133750D01*
X1491899Y155965D01*
Y454588D01*
X1543997Y506686D01*
Y567282D01*
X1491387Y619892D01*
Y930860D01*
X1494662Y934135D01*
Y1140800D01*
X1498100Y1144238D01*
Y1150227D01*
X1494662Y1153665D01*
Y1336000D01*
G01X1489000Y723000D02*
Y619450D01*
X1541997Y566453D01*
Y507515D01*
X1489899Y455417D01*
Y152249D01*
X1511177Y130971D01*
Y125412D01*
G01X1568000Y548500D02*
Y578503D01*
X1534300Y612203D01*
Y665700D01*
X1526000Y674000D01*
Y728000D01*
G01X1788726Y1034726D02*
X1870895D01*
X1874450Y1038281D01*
Y1089980D01*
X1873579Y1090851D01*
Y1092675D01*
X1874450Y1093546D01*
Y1328050D01*
X1873500Y1329000D01*
G54D16*
G01X363248Y-425196D02*
Y-505196D01*
G01D02*
X1639148D01*
G01X359248Y-409196D02*
G02I-12000J0D01*
G01X354098D02*
G02I-6850J0D01*
G01X347248Y-425196D02*
Y-393196D01*
G01X363248Y-425196D02*
X1639148D01*
G01X363248Y-460696D02*
X1639148D01*
G01X363248Y-409196D02*
X331248D01*
G01X468472Y182441D02*
X468373Y182540D01*
Y200431D01*
X492851Y224909D01*
Y230038D01*
X515324Y252511D01*
G01X619171Y112329D02*
X598236Y133264D01*
Y181981D01*
G01D02*
Y185273D01*
X608800Y195837D01*
Y217274D01*
X639537Y248011D01*
G01X772900Y1328550D02*
Y1295200D01*
X724600Y1246900D01*
Y1066885D01*
X699483Y1041768D01*
Y654934D01*
X700000Y654417D01*
G01X720748Y-425196D02*
Y-505196D01*
G01X710000Y1107173D02*
X721600Y1118773D01*
Y1248432D01*
X769728Y1296560D01*
Y1325747D01*
G01X858248Y-425196D02*
Y-505196D01*
G01X874807Y375193D02*
Y355805D01*
X874800Y355798D01*
G01X878500Y476000D02*
Y474700D01*
X874710Y470910D01*
Y418510D01*
X871100Y414900D01*
Y382900D01*
X874807Y379193D01*
Y375193D01*
G01X863851Y1501681D02*
X866052Y1499480D01*
Y1312128D01*
X863800Y1309876D01*
G01X873918Y1411149D02*
X870688Y1407919D01*
Y1368376D01*
X873259Y1365805D01*
G01X973248Y-425196D02*
Y-505196D01*
G01X969463Y1177599D02*
X973459Y1181595D01*
Y1268086D01*
X1025335Y1319962D01*
Y1324216D01*
G01X1028000Y1404700D02*
X1025435Y1402135D01*
X1025284D01*
Y1341216D01*
G01X1092200Y1125800D02*
Y1124948D01*
X1083355Y1116103D01*
G01X1271648Y-425196D02*
Y-505196D01*
G01X1314794Y162944D02*
X1311756D01*
X1293417Y181283D01*
Y206253D01*
X1252653Y247017D01*
X1250016D01*
G01X1441648Y-425196D02*
Y-505196D01*
G01X1483268Y96654D02*
Y102166D01*
G01X1639148Y-425196D02*
Y-505196D01*
G01X1667148Y-409196D02*
G02I-12000J0D01*
G01X1661998D02*
G02I-6850J0D01*
G01X1655148Y-425196D02*
Y-393196D01*
G01X1671148Y-409196D02*
X1639148D01*
G54D17*
G01X394744Y-485863D02*
X395618Y-484988D01*
X396273Y-483530D01*
X396710Y-481487D01*
X396273Y-479738D01*
X395400Y-478571D01*
X393871Y-477696D01*
X387976D01*
Y-495196D01*
X395181D01*
X396710Y-494030D01*
X397583Y-492279D01*
X398020Y-490238D01*
X397583Y-488196D01*
X396273Y-486446D01*
X394744Y-485863D01*
X387976D01*
G01X407441Y-495196D02*
Y-483530D01*
G01Y-485863D02*
X408533Y-484696D01*
X409625Y-483821D01*
X411153Y-483530D01*
X412244Y-483821D01*
X413555Y-484696D01*
G01X423413Y-500446D02*
X424723Y-501029D01*
X426470Y-500446D01*
X427561Y-499280D01*
X428435Y-497821D01*
X429744Y-493155D01*
X432583Y-483530D01*
G01X425596D02*
X429744Y-493155D01*
G01X448991Y-484988D02*
X447463Y-483821D01*
X446153Y-483530D01*
X444406Y-484113D01*
X443096Y-485279D01*
X442223Y-487321D01*
X442004Y-489363D01*
X442223Y-491405D01*
X443096Y-493155D01*
X444406Y-494613D01*
X446153Y-495196D01*
X447681Y-494613D01*
X448991Y-493446D01*
G01X459723Y-487321D02*
X466710D01*
X466055Y-485279D01*
X464963Y-484113D01*
X463435Y-483530D01*
X461906Y-483821D01*
X460596Y-484696D01*
X459723Y-486738D01*
X459286Y-488488D01*
Y-490238D01*
X459723Y-491988D01*
X460815Y-493738D01*
X462125Y-494904D01*
X463653Y-495196D01*
X465181Y-494613D01*
X466710Y-492863D01*
G01X502801Y-479155D02*
X501491Y-478279D01*
X499963Y-477696D01*
X498216D01*
X496251Y-478571D01*
X494723Y-480029D01*
X493631Y-481780D01*
X492758Y-484696D01*
X492539Y-487321D01*
X492976Y-489946D01*
X493631Y-491696D01*
X494941Y-493446D01*
X496470Y-494613D01*
X497998Y-495196D01*
X499526D01*
X501055Y-494613D01*
X502365Y-493738D01*
X503457Y-492572D01*
G01X519428Y-495196D02*
Y-483530D01*
G01Y-485571D02*
X518555Y-484405D01*
X517244Y-483821D01*
X515716Y-483530D01*
X514188Y-484113D01*
X512878Y-485279D01*
X512004Y-487029D01*
X511568Y-489363D01*
X512004Y-491696D01*
X512878Y-493446D01*
X514188Y-494613D01*
X515716Y-495196D01*
X517244Y-494904D01*
X518555Y-494030D01*
X519428Y-492863D01*
G01X529286Y-495196D02*
Y-483530D01*
G01Y-486446D02*
X530160Y-484988D01*
X531470Y-483821D01*
X533216Y-483530D01*
X534744Y-483821D01*
X536055Y-484988D01*
X536710Y-487029D01*
Y-495196D01*
G01X545913Y-500446D02*
X547223Y-501029D01*
X548970Y-500446D01*
X550061Y-499280D01*
X550935Y-497821D01*
X552244Y-493155D01*
X555083Y-483530D01*
G01X548096D02*
X552244Y-493155D01*
G01X567998Y-495196D02*
X566688Y-494904D01*
X565378Y-493738D01*
X564504Y-491696D01*
X564068Y-489363D01*
X564504Y-487029D01*
X565378Y-484988D01*
X566688Y-483821D01*
X567998Y-483530D01*
X569308Y-483821D01*
X570618Y-484988D01*
X571491Y-487029D01*
X571710Y-489363D01*
X571491Y-491696D01*
X570618Y-493738D01*
X569308Y-494904D01*
X567998Y-495196D01*
G01X581786D02*
Y-483530D01*
G01Y-486446D02*
X582660Y-484988D01*
X583970Y-483821D01*
X585716Y-483530D01*
X587244Y-483821D01*
X588555Y-484988D01*
X589210Y-487029D01*
Y-495196D01*
G01X616350D02*
Y-477696D01*
X624646D01*
G01X621590Y-486154D02*
X616350D01*
G01X637998Y-495779D02*
X637561Y-495488D01*
Y-494904D01*
X637998Y-494613D01*
X638435Y-494904D01*
Y-495488D01*
X637998Y-495779D01*
G01X650695Y-495196D02*
Y-477696D01*
X655061D01*
X656808Y-478571D01*
X658118Y-479738D01*
X659210Y-481487D01*
X660083Y-483530D01*
X660301Y-486446D01*
X660083Y-489363D01*
X659210Y-491405D01*
X658118Y-493155D01*
X656808Y-494321D01*
X655061Y-495196D01*
X650695D01*
G01X668631D02*
Y-477696D01*
X673871D01*
X675618Y-478571D01*
X676928Y-480613D01*
X677365Y-482946D01*
X676928Y-485279D01*
X675836Y-487029D01*
X673871Y-487905D01*
X668631D01*
G01X692244Y-485863D02*
X693118Y-484988D01*
X693773Y-483530D01*
X694210Y-481487D01*
X693773Y-479738D01*
X692900Y-478571D01*
X691371Y-477696D01*
X685476D01*
Y-495196D01*
X692681D01*
X694210Y-494030D01*
X695083Y-492279D01*
X695520Y-490238D01*
X695083Y-488196D01*
X693773Y-486446D01*
X692244Y-485863D01*
X685476D01*
G01X501071Y-450196D02*
Y-432696D01*
X506748Y-447279D01*
X512425Y-432696D01*
Y-450196D01*
G01X524248D02*
X522938Y-449904D01*
X521628Y-448738D01*
X520754Y-446696D01*
X520318Y-444363D01*
X520754Y-442029D01*
X521628Y-439988D01*
X522938Y-438821D01*
X524248Y-438530D01*
X525558Y-438821D01*
X526868Y-439988D01*
X527741Y-442029D01*
X527960Y-444363D01*
X527741Y-446696D01*
X526868Y-448738D01*
X525558Y-449904D01*
X524248Y-450196D01*
G01X545678Y-432696D02*
Y-450196D01*
G01Y-447572D02*
X544805Y-449030D01*
X543494Y-449904D01*
X541966Y-450196D01*
X540220Y-449613D01*
X538910Y-448155D01*
X538036Y-446405D01*
X537818Y-444363D01*
X538036Y-442321D01*
X538910Y-440571D01*
X540220Y-439113D01*
X541966Y-438530D01*
X543494Y-438821D01*
X544586Y-439405D01*
X545678Y-440571D01*
G01X555973Y-442321D02*
X562960D01*
X562305Y-440279D01*
X561213Y-439113D01*
X559685Y-438530D01*
X558156Y-438821D01*
X556846Y-439696D01*
X555973Y-441738D01*
X555536Y-443488D01*
Y-445238D01*
X555973Y-446988D01*
X557065Y-448738D01*
X558375Y-449904D01*
X559903Y-450196D01*
X561431Y-449613D01*
X562960Y-447863D01*
G01X576748Y-450196D02*
Y-432696D01*
G01X754448Y-495196D02*
Y-477696D01*
X751828Y-481196D01*
G01Y-495196D02*
X757068D01*
G01X767800Y-487905D02*
X769328Y-485863D01*
X770638Y-484696D01*
X772385Y-484113D01*
X773913Y-484696D01*
X775005Y-485863D01*
X775878Y-487613D01*
X776096Y-489654D01*
X775878Y-491405D01*
X775005Y-493155D01*
X773694Y-494613D01*
X772166Y-495196D01*
X770420Y-494613D01*
X768891Y-492863D01*
X768018Y-490238D01*
X767800Y-487321D01*
X768236Y-483530D01*
X768891Y-481487D01*
X769983Y-479446D01*
X771511Y-477988D01*
X773040Y-477696D01*
X774568Y-478279D01*
X775660Y-479738D01*
G01X784645Y-491696D02*
X785954Y-493738D01*
X787701Y-494904D01*
X789666Y-495196D01*
X791413Y-494904D01*
X793160Y-493446D01*
X794251Y-491696D01*
X794470Y-489946D01*
X794033Y-487905D01*
X792505Y-486446D01*
X790976Y-485863D01*
X789011D01*
G01X790976D02*
X792286Y-484988D01*
X793378Y-483530D01*
X793815Y-481780D01*
X793378Y-480029D01*
X792286Y-478571D01*
X790321Y-477696D01*
X788356Y-477988D01*
X786391Y-479155D01*
G01X806948Y-495196D02*
Y-477696D01*
X804328Y-481196D01*
G01Y-495196D02*
X809568D01*
G01X819645Y-492572D02*
X820954Y-494030D01*
X822483Y-494904D01*
X824448Y-495196D01*
X826413Y-494613D01*
X827941Y-493446D01*
X829033Y-491405D01*
X829251Y-489071D01*
X828815Y-486738D01*
X827723Y-485279D01*
X826194Y-484113D01*
X824666Y-483821D01*
X823138Y-484113D01*
X821173Y-485279D01*
X821828Y-477696D01*
X827723D01*
G01X741331Y-450196D02*
Y-432696D01*
X746571D01*
X748318Y-433571D01*
X749628Y-435613D01*
X750065Y-437946D01*
X749628Y-440279D01*
X748536Y-442029D01*
X746571Y-442905D01*
X741331D01*
G01X768001Y-434155D02*
X766691Y-433279D01*
X765163Y-432696D01*
X763416D01*
X761451Y-433571D01*
X759923Y-435029D01*
X758831Y-436780D01*
X757958Y-439696D01*
X757739Y-442321D01*
X758176Y-444946D01*
X758831Y-446696D01*
X760141Y-448446D01*
X761670Y-449613D01*
X763198Y-450196D01*
X764726D01*
X766255Y-449613D01*
X767565Y-448738D01*
X768657Y-447572D01*
G01X782444Y-440863D02*
X783318Y-439988D01*
X783973Y-438530D01*
X784410Y-436487D01*
X783973Y-434738D01*
X783100Y-433571D01*
X781571Y-432696D01*
X775676D01*
Y-450196D01*
X782881D01*
X784410Y-449030D01*
X785283Y-447279D01*
X785720Y-445238D01*
X785283Y-443196D01*
X783973Y-441446D01*
X782444Y-440863D01*
X775676D01*
G01X791648Y-456029D02*
X804748D01*
G01X810676Y-450196D02*
Y-432696D01*
X820720Y-450196D01*
Y-432696D01*
G01X833198Y-450196D02*
X831451Y-449904D01*
X829923Y-448738D01*
X828613Y-446988D01*
X827739Y-444946D01*
X827303Y-442613D01*
Y-440279D01*
X827739Y-437946D01*
X828613Y-435904D01*
X829923Y-434155D01*
X831451Y-432988D01*
X833198Y-432696D01*
X834944Y-432988D01*
X836473Y-434155D01*
X837783Y-435904D01*
X838657Y-437946D01*
X839093Y-440279D01*
Y-442613D01*
X838657Y-444946D01*
X837783Y-446988D01*
X836473Y-448738D01*
X834944Y-449904D01*
X833198Y-450196D01*
G01X884039Y-432696D02*
X889498Y-450196D01*
X894957Y-432696D01*
G01X911365Y-450196D02*
X902631D01*
Y-432696D01*
X911365D01*
G01X907871Y-441154D02*
X902631D01*
G01X920131Y-450196D02*
Y-432696D01*
X925590D01*
X927336Y-433571D01*
X928428Y-434738D01*
X928865Y-437071D01*
X928428Y-439405D01*
X927118Y-440863D01*
X925590Y-441738D01*
X920131D01*
G01X925590D02*
X928865Y-450196D01*
G01X941998Y-450779D02*
X941561Y-450488D01*
Y-449904D01*
X941998Y-449613D01*
X942435Y-449904D01*
Y-450488D01*
X941998Y-450779D01*
G01X915748Y-495196D02*
Y-477696D01*
X913128Y-481196D01*
G01Y-495196D02*
X918368D01*
G01X1082981Y-432696D02*
Y-450196D01*
X1091715D01*
G01X1108778D02*
Y-438530D01*
G01Y-440571D02*
X1107905Y-439405D01*
X1106594Y-438821D01*
X1105066Y-438530D01*
X1103538Y-439113D01*
X1102228Y-440279D01*
X1101354Y-442029D01*
X1100918Y-444363D01*
X1101354Y-446696D01*
X1102228Y-448446D01*
X1103538Y-449613D01*
X1105066Y-450196D01*
X1106594Y-449904D01*
X1107905Y-449030D01*
X1108778Y-447863D01*
G01X1117763Y-455446D02*
X1119073Y-456029D01*
X1120820Y-455446D01*
X1121911Y-454280D01*
X1122785Y-452821D01*
X1124094Y-448155D01*
X1126933Y-438530D01*
G01X1119946D02*
X1124094Y-448155D01*
G01X1136573Y-442321D02*
X1143560D01*
X1142905Y-440279D01*
X1141813Y-439113D01*
X1140285Y-438530D01*
X1138756Y-438821D01*
X1137446Y-439696D01*
X1136573Y-441738D01*
X1136136Y-443488D01*
Y-445238D01*
X1136573Y-446988D01*
X1137665Y-448738D01*
X1138975Y-449904D01*
X1140503Y-450196D01*
X1142031Y-449613D01*
X1143560Y-447863D01*
G01X1154291Y-450196D02*
Y-438530D01*
G01Y-440863D02*
X1155383Y-439696D01*
X1156475Y-438821D01*
X1158003Y-438530D01*
X1159094Y-438821D01*
X1160405Y-439696D01*
G01X1109231Y-477696D02*
Y-495196D01*
X1117965D01*
G01X1126295Y-492572D02*
X1127604Y-494030D01*
X1129133Y-494904D01*
X1131098Y-495196D01*
X1133063Y-494613D01*
X1134591Y-493446D01*
X1135683Y-491405D01*
X1135901Y-489071D01*
X1135465Y-486738D01*
X1134373Y-485279D01*
X1132844Y-484113D01*
X1131316Y-483821D01*
X1129788Y-484113D01*
X1127823Y-485279D01*
X1128478Y-477696D01*
X1134373D01*
G01X1312898Y-495196D02*
X1311151Y-494904D01*
X1309623Y-493738D01*
X1308313Y-491988D01*
X1307439Y-489946D01*
X1307003Y-487613D01*
Y-485279D01*
X1307439Y-482946D01*
X1308313Y-480904D01*
X1309623Y-479155D01*
X1311151Y-477988D01*
X1312898Y-477696D01*
X1314644Y-477988D01*
X1316173Y-479155D01*
X1317483Y-480904D01*
X1318357Y-482946D01*
X1318793Y-485279D01*
Y-487613D01*
X1318357Y-489946D01*
X1317483Y-491988D01*
X1316173Y-493738D01*
X1314644Y-494904D01*
X1312898Y-495196D01*
G01X1314644Y-490529D02*
X1317265Y-495196D01*
G01X1325595Y-477696D02*
Y-490238D01*
X1326468Y-492863D01*
X1328215Y-494613D01*
X1330398Y-495196D01*
X1332581Y-494613D01*
X1334328Y-492863D01*
X1335201Y-490238D01*
Y-477696D01*
G01X1345278D02*
X1350518D01*
G01X1347898D02*
Y-495196D01*
G01X1345278D02*
X1350518D01*
G01X1360376D02*
Y-477696D01*
X1370420Y-495196D01*
Y-477696D01*
G01X1387701Y-479155D02*
X1386391Y-478279D01*
X1384863Y-477696D01*
X1383116D01*
X1381151Y-478571D01*
X1379623Y-480029D01*
X1378531Y-481780D01*
X1377658Y-484696D01*
X1377439Y-487321D01*
X1377876Y-489946D01*
X1378531Y-491696D01*
X1379841Y-493446D01*
X1381370Y-494613D01*
X1382898Y-495196D01*
X1384426D01*
X1385955Y-494613D01*
X1387265Y-493738D01*
X1388357Y-492572D01*
G01X1400398Y-495196D02*
Y-487321D01*
X1396031Y-477696D01*
G01X1404765D02*
X1400398Y-487321D01*
G01X1290595Y-450196D02*
Y-432696D01*
X1294961D01*
X1296708Y-433571D01*
X1298018Y-434738D01*
X1299110Y-436487D01*
X1299983Y-438530D01*
X1300201Y-441446D01*
X1299983Y-444363D01*
X1299110Y-446405D01*
X1298018Y-448155D01*
X1296708Y-449321D01*
X1294961Y-450196D01*
X1290595D01*
G01X1309623Y-442321D02*
X1316610D01*
X1315955Y-440279D01*
X1314863Y-439113D01*
X1313335Y-438530D01*
X1311806Y-438821D01*
X1310496Y-439696D01*
X1309623Y-441738D01*
X1309186Y-443488D01*
Y-445238D01*
X1309623Y-446988D01*
X1310715Y-448738D01*
X1312025Y-449904D01*
X1313553Y-450196D01*
X1315081Y-449613D01*
X1316610Y-447863D01*
G01X1327123Y-448155D02*
X1328215Y-449321D01*
X1329743Y-450196D01*
X1331053D01*
X1332363Y-449613D01*
X1333236Y-448738D01*
X1333673Y-447572D01*
X1333455Y-445821D01*
X1332581Y-444946D01*
X1328651Y-443196D01*
X1327778Y-441154D01*
X1328215Y-439696D01*
X1329088Y-438821D01*
X1330398Y-438530D01*
X1331708Y-438821D01*
X1333018Y-439696D01*
G01X1347898Y-438530D02*
Y-450196D01*
G01Y-433863D02*
X1347461Y-433571D01*
Y-432988D01*
X1347898Y-432696D01*
X1348335Y-432988D01*
Y-433571D01*
X1347898Y-433863D01*
G01X1362341Y-454571D02*
X1363870Y-455738D01*
X1365616Y-456029D01*
X1367144Y-455738D01*
X1368455Y-454280D01*
X1369328Y-452238D01*
Y-438530D01*
G01Y-440863D02*
X1368455Y-439696D01*
X1367144Y-438821D01*
X1365616Y-438530D01*
X1363870Y-439113D01*
X1362778Y-440279D01*
X1361904Y-442321D01*
X1361468Y-444363D01*
X1361686Y-446113D01*
X1362560Y-448155D01*
X1363870Y-449613D01*
X1365616Y-450196D01*
X1366926Y-449904D01*
X1368455Y-448738D01*
X1369328Y-447572D01*
G01X1379186Y-450196D02*
Y-438530D01*
G01Y-441446D02*
X1380060Y-439988D01*
X1381370Y-438821D01*
X1383116Y-438530D01*
X1384644Y-438821D01*
X1385955Y-439988D01*
X1386610Y-442029D01*
Y-450196D01*
G01X1397123Y-442321D02*
X1404110D01*
X1403455Y-440279D01*
X1402363Y-439113D01*
X1400835Y-438530D01*
X1399306Y-438821D01*
X1397996Y-439696D01*
X1397123Y-441738D01*
X1396686Y-443488D01*
Y-445238D01*
X1397123Y-446988D01*
X1398215Y-448738D01*
X1399525Y-449904D01*
X1401053Y-450196D01*
X1402581Y-449613D01*
X1404110Y-447863D01*
G01X1414841Y-450196D02*
Y-438530D01*
G01Y-440863D02*
X1415933Y-439696D01*
X1417025Y-438821D01*
X1418553Y-438530D01*
X1419644Y-438821D01*
X1420955Y-439696D01*
G01X1461598Y-477696D02*
X1459851Y-478279D01*
X1458541Y-479738D01*
X1457668Y-481487D01*
X1457013Y-483821D01*
X1456795Y-486446D01*
X1457013Y-489071D01*
X1457668Y-491405D01*
X1458541Y-493155D01*
X1459851Y-494613D01*
X1461598Y-495196D01*
X1463344Y-494613D01*
X1464655Y-493155D01*
X1465528Y-491405D01*
X1466183Y-489071D01*
X1466401Y-486446D01*
X1466183Y-483821D01*
X1465528Y-481487D01*
X1464655Y-479738D01*
X1463344Y-478279D01*
X1461598Y-477696D01*
G01X1474950Y-487905D02*
X1476478Y-485863D01*
X1477788Y-484696D01*
X1479535Y-484113D01*
X1481063Y-484696D01*
X1482155Y-485863D01*
X1483028Y-487613D01*
X1483246Y-489654D01*
X1483028Y-491405D01*
X1482155Y-493155D01*
X1480844Y-494613D01*
X1479316Y-495196D01*
X1477570Y-494613D01*
X1476041Y-492863D01*
X1475168Y-490238D01*
X1474950Y-487321D01*
X1475386Y-483530D01*
X1476041Y-481487D01*
X1477133Y-479446D01*
X1478661Y-477988D01*
X1480190Y-477696D01*
X1481718Y-478279D01*
X1482810Y-479738D01*
G01X1492668Y-495779D02*
X1500528Y-477696D01*
G01X1514098D02*
X1512351Y-478279D01*
X1511041Y-479738D01*
X1510168Y-481487D01*
X1509513Y-483821D01*
X1509295Y-486446D01*
X1509513Y-489071D01*
X1510168Y-491405D01*
X1511041Y-493155D01*
X1512351Y-494613D01*
X1514098Y-495196D01*
X1515844Y-494613D01*
X1517155Y-493155D01*
X1518028Y-491405D01*
X1518683Y-489071D01*
X1518901Y-486446D01*
X1518683Y-483821D01*
X1518028Y-481487D01*
X1517155Y-479738D01*
X1515844Y-478279D01*
X1514098Y-477696D01*
G01X1527886Y-493155D02*
X1529415Y-494613D01*
X1531161Y-495196D01*
X1532908Y-494613D01*
X1534436Y-492863D01*
X1535528Y-490238D01*
X1535965Y-487613D01*
Y-484405D01*
X1535528Y-481780D01*
X1534436Y-479446D01*
X1533126Y-478279D01*
X1531598Y-477696D01*
X1529851Y-478279D01*
X1528541Y-479446D01*
X1527668Y-481196D01*
X1527231Y-483530D01*
X1527668Y-485571D01*
X1528760Y-487613D01*
X1530070Y-488780D01*
X1531598Y-489071D01*
X1533344Y-488488D01*
X1534655Y-487029D01*
X1535965Y-484405D01*
G01X1545168Y-495779D02*
X1553028Y-477696D01*
G01X1562450Y-480613D02*
X1563760Y-478863D01*
X1565288Y-477988D01*
X1567035Y-477696D01*
X1569218Y-478279D01*
X1570746Y-479738D01*
X1571183Y-481487D01*
X1570965Y-483238D01*
X1570091Y-484696D01*
X1565725Y-487613D01*
X1563760Y-489654D01*
X1562450Y-492572D01*
X1562013Y-495196D01*
X1571183D01*
G01X1584098Y-477696D02*
X1582351Y-478279D01*
X1581041Y-479738D01*
X1580168Y-481487D01*
X1579513Y-483821D01*
X1579295Y-486446D01*
X1579513Y-489071D01*
X1580168Y-491405D01*
X1581041Y-493155D01*
X1582351Y-494613D01*
X1584098Y-495196D01*
X1585844Y-494613D01*
X1587155Y-493155D01*
X1588028Y-491405D01*
X1588683Y-489071D01*
X1588901Y-486446D01*
X1588683Y-483821D01*
X1588028Y-481487D01*
X1587155Y-479738D01*
X1585844Y-478279D01*
X1584098Y-477696D01*
G01X1601598Y-495196D02*
Y-477696D01*
X1598978Y-481196D01*
G01Y-495196D02*
X1604218D01*
G01X1618661D02*
X1619098Y-491405D01*
X1619753Y-488196D01*
X1620626Y-485279D01*
X1621718Y-482071D01*
X1623465Y-477696D01*
X1614731D01*
G01X1509295Y-450196D02*
Y-432696D01*
X1513661D01*
X1515408Y-433571D01*
X1516718Y-434738D01*
X1517810Y-436487D01*
X1518683Y-438530D01*
X1518901Y-441446D01*
X1518683Y-444363D01*
X1517810Y-446405D01*
X1516718Y-448155D01*
X1515408Y-449321D01*
X1513661Y-450196D01*
X1509295D01*
G01X1535528D02*
Y-438530D01*
G01Y-440571D02*
X1534655Y-439405D01*
X1533344Y-438821D01*
X1531816Y-438530D01*
X1530288Y-439113D01*
X1528978Y-440279D01*
X1528104Y-442029D01*
X1527668Y-444363D01*
X1528104Y-446696D01*
X1528978Y-448446D01*
X1530288Y-449613D01*
X1531816Y-450196D01*
X1533344Y-449904D01*
X1534655Y-449030D01*
X1535528Y-447863D01*
G01X1549098Y-432696D02*
Y-450196D01*
G01X1546041Y-438530D02*
X1552155D01*
G01X1563323Y-442321D02*
X1570310D01*
X1569655Y-440279D01*
X1568563Y-439113D01*
X1567035Y-438530D01*
X1565506Y-438821D01*
X1564196Y-439696D01*
X1563323Y-441738D01*
X1562886Y-443488D01*
Y-445238D01*
X1563323Y-446988D01*
X1564415Y-448738D01*
X1565725Y-449904D01*
X1567253Y-450196D01*
X1568781Y-449613D01*
X1570310Y-447863D01*
G54D18*
G01X47607Y527511D02*
X20089D01*
X12891Y534709D01*
Y839759D01*
X48252Y875120D01*
Y1004339D01*
X17512Y1035079D01*
Y1209896D01*
X31558Y1223942D01*
X31500Y1224000D01*
G01X19712Y1176350D02*
Y1035991D01*
X50452Y1005251D01*
Y873951D01*
X17899Y841398D01*
Y533489D01*
X21677Y529711D01*
X59638D01*
X61834Y527515D01*
G01X171861Y527469D02*
X167419Y531911D01*
X22589D01*
X20099Y534401D01*
Y840486D01*
X52652Y873039D01*
Y1006163D01*
X33355Y1025460D01*
Y1176690D01*
X39425Y1182760D01*
Y1226200D01*
G01X36848Y1173600D02*
X35555Y1172307D01*
Y1138142D01*
X35055Y1137642D01*
Y1026872D01*
X54852Y1007075D01*
Y872127D01*
X22298Y839573D01*
Y536902D01*
X24900Y534300D01*
X179261D01*
X186088Y527473D01*
G01X41381Y1335567D02*
X34196Y1328382D01*
Y1186546D01*
X23700Y1176050D01*
Y1119061D01*
X26723Y1116038D01*
G01X45518Y1336366D02*
X41625Y1332473D01*
Y1141100D01*
X37255Y1136730D01*
Y1027784D01*
X60952Y1004087D01*
Y873852D01*
X27600Y840500D01*
Y708368D01*
X25200Y705968D01*
Y679800D01*
X27143Y677857D01*
Y663071D01*
G01X39325Y1131400D02*
Y1028826D01*
X63152Y1004999D01*
Y872940D01*
X29800Y839588D01*
Y707100D01*
X27510Y704810D01*
Y688422D01*
G01X27090Y1141389D02*
Y1174358D01*
X37225Y1184493D01*
Y1230100D01*
G01X268100Y982300D02*
Y754400D01*
X270650Y751850D01*
Y733038D01*
X281000Y722688D01*
Y706100D01*
X278700Y703800D01*
Y630518D01*
X299653Y609565D01*
Y561840D01*
X257597Y519784D01*
Y295397D01*
X253200Y291000D01*
X146600D01*
X91800Y236200D01*
Y198700D01*
X90200Y197100D01*
Y181898D01*
X95437Y176661D01*
G01X85146Y621637D02*
Y628646D01*
X99600Y643100D01*
Y713299D01*
X113637Y727336D01*
Y732837D01*
X197600Y816800D01*
Y920900D01*
X199900Y923200D01*
G01X95537Y1082173D02*
X97700Y1080010D01*
Y1045800D01*
X106700Y1036800D01*
X229400D01*
X239500Y1026700D01*
Y986100D01*
X239000Y985600D01*
G01X281500Y1036744D02*
X272100Y1027344D01*
Y997988D01*
X270600Y996488D01*
Y755600D01*
X272850Y753350D01*
Y733950D01*
X283700Y723100D01*
Y705600D01*
X281500Y703400D01*
Y630830D01*
X301853Y610477D01*
Y560928D01*
X259797Y518872D01*
Y294485D01*
X254111Y288799D01*
X147511D01*
X145437Y286725D01*
Y265561D01*
G01X150253Y709713D02*
Y758463D01*
X207500Y815710D01*
Y918200D01*
X250699Y961399D01*
Y980699D01*
X255500Y985500D01*
Y988364D01*
X255499Y988365D01*
Y993835D01*
X258500Y996836D01*
Y1076000D01*
X249307Y1085193D01*
Y1221442D01*
X279900Y1252035D01*
Y1328300D01*
G01X145437Y717617D02*
Y757837D01*
X202000Y814400D01*
Y915812D01*
X248099Y961911D01*
Y1001101D01*
X244600Y1004600D01*
G01X140364Y749807D02*
Y756452D01*
X199800Y815888D01*
Y916724D01*
X242099Y959023D01*
Y1033901D01*
X226205Y1049795D01*
Y1072605D01*
X208037Y1090773D01*
X198427D01*
X195100Y1094100D01*
Y1096800D01*
G01X145437Y1165673D02*
Y1089863D01*
X148400Y1086900D01*
G01X150862Y1152723D02*
Y1210862D01*
X166000Y1226000D01*
Y1342700D01*
X163500Y1345200D01*
G01X148311Y1182767D02*
Y1228789D01*
X148300Y1228800D01*
G01X273300Y981700D02*
X273000Y981400D01*
Y757700D01*
X286536Y744164D01*
Y628906D01*
X304053Y611389D01*
Y560016D01*
X262597Y518560D01*
Y244897D01*
X214100Y196400D01*
Y182310D01*
X219749Y176661D01*
G01X223100Y920600D02*
X217494Y914994D01*
Y652500D01*
X214000Y649006D01*
Y624666D01*
X219749Y618917D01*
G01X258600Y715500D02*
Y754564D01*
X257699Y755465D01*
Y992923D01*
X261100Y996324D01*
Y1005700D01*
G01X274520Y709457D02*
X268450Y715527D01*
Y750938D01*
X262099Y757289D01*
Y991099D01*
X269900Y998900D01*
Y1039600D01*
X273364Y1043064D01*
Y1127760D01*
X262512Y1138612D01*
Y1154434D01*
X272876Y1164798D01*
Y1176924D01*
X270070Y1179730D01*
Y1237170D01*
X283700Y1250800D01*
Y1328300D01*
G01X264731Y749551D02*
X261800Y752482D01*
Y754476D01*
X259899Y756377D01*
Y992011D01*
X267700Y999812D01*
Y1056300D01*
X264864Y1059136D01*
Y1120500D01*
G01X252100Y990100D02*
Y1068200D01*
X246688Y1073612D01*
X228310D01*
X219749Y1082173D01*
G01X271100Y1063200D02*
X271164Y1063264D01*
Y1126334D01*
X260312Y1137186D01*
Y1156336D01*
X269649Y1165673D01*
G01X291601Y418503D02*
X291697Y418407D01*
Y212003D01*
X356838Y146862D01*
Y64838D01*
X354100Y62100D01*
G01X280800Y1011900D02*
Y1011400D01*
X279362Y1009962D01*
Y757705D01*
X290867Y746200D01*
Y630428D01*
X308493Y612802D01*
Y558603D01*
X269535Y519645D01*
Y269116D01*
X271588Y267063D01*
Y259426D01*
X269262Y257100D01*
Y215665D01*
X269500Y215427D01*
Y215100D01*
X335400Y149200D01*
Y112321D01*
X345321Y102400D01*
G01X295900Y1339700D02*
X298038Y1337562D01*
Y1329438D01*
X295900Y1327300D01*
Y1084400D01*
X299200Y1081100D01*
Y753040D01*
X301593Y750647D01*
Y718736D01*
X310429Y709900D01*
Y634613D01*
X319465Y625577D01*
Y554402D01*
X286340Y521277D01*
Y494060D01*
X287497Y492903D01*
Y213504D01*
X350441Y150560D01*
Y117541D01*
G01X296100Y1335100D02*
X293263Y1332263D01*
Y1206112D01*
X294275Y1205100D01*
Y1083726D01*
X297575Y1080426D01*
Y752366D01*
X299968Y749973D01*
Y718062D01*
X305240Y712790D01*
Y636491D01*
X317840Y623891D01*
Y555076D01*
X282997Y520233D01*
Y215705D01*
X347881Y150821D01*
Y114881D01*
G01X292600Y1337367D02*
X291638Y1336405D01*
Y1205062D01*
X292650Y1204050D01*
Y754992D01*
X298343Y749299D01*
Y717388D01*
X300778Y714953D01*
Y638654D01*
X316215Y623217D01*
Y555750D01*
X280397Y519932D01*
Y216006D01*
X346223Y150180D01*
Y119823D01*
X345321Y118921D01*
G01X281200Y1033000D02*
X277400Y1029200D01*
Y756926D01*
X288736Y745590D01*
Y629818D01*
X306325Y612229D01*
Y559176D01*
X267597Y520448D01*
Y268313D01*
X269649Y266261D01*
G01X296032Y527469D02*
X321701Y553138D01*
Y629380D01*
X316100Y634981D01*
Y708688D01*
X308999Y715789D01*
Y1097911D01*
X315596Y1104508D01*
Y1216604D01*
X315500Y1216700D01*
G01X310259Y527473D02*
Y536759D01*
X327401Y553901D01*
Y626792D01*
X318300Y635893D01*
Y709600D01*
X311200Y716700D01*
Y1097000D01*
X318125Y1103925D01*
Y1162246D01*
X331679Y1175800D01*
G01X275385Y1152596D02*
Y1163879D01*
X280697Y1169191D01*
Y1201697D01*
X285900Y1206900D01*
Y1349459D01*
X286100Y1349659D01*
G01X273243Y1182915D02*
Y1226243D01*
X276100Y1229100D01*
G01X337100Y972100D02*
X340100Y969100D01*
Y742512D01*
X346800Y735812D01*
Y628300D01*
X337500Y619000D01*
Y316600D01*
X346800Y307300D01*
Y179199D01*
X344062Y176461D01*
G01X350673Y1031200D02*
Y969473D01*
X343000Y961800D01*
Y759100D01*
X346550Y755550D01*
Y740323D01*
X350673Y736200D01*
Y629061D01*
X339700Y618088D01*
Y332319D01*
X386800Y285219D01*
Y263800D01*
G01X335300Y926900D02*
X337900Y924300D01*
Y741600D01*
X343400Y736100D01*
Y639388D01*
X333682Y629670D01*
Y621858D01*
G01X344062Y1082073D02*
X341900Y1079911D01*
Y998474D01*
X344737Y995637D01*
G01X429724Y110827D02*
X423936Y116615D01*
Y149892D01*
X402465Y171363D01*
Y329835D01*
X418600Y345970D01*
Y445462D01*
G01X429724Y102166D02*
X421107Y110783D01*
Y148879D01*
X399727Y170259D01*
Y330970D01*
X412744Y343987D01*
Y493521D01*
X403783Y502482D01*
Y673898D01*
X416096Y686211D01*
Y1045293D01*
X416981Y1046178D01*
Y1060753D01*
X400442Y1077292D01*
Y1151399D01*
X413870Y1164827D01*
Y1243291D01*
X422373Y1251794D01*
Y1359747D01*
G01X429724Y96654D02*
X417869Y108509D01*
Y147826D01*
X396727Y168968D01*
Y332213D01*
X409544Y345030D01*
Y492478D01*
X399488Y502534D01*
Y673846D01*
X414471Y688829D01*
Y1045967D01*
X415356Y1046852D01*
Y1058135D01*
X397441Y1076050D01*
Y1078534D01*
X397442Y1078535D01*
Y1152642D01*
X410870Y1166070D01*
Y1244534D01*
X418922Y1252586D01*
Y1356522D01*
G01X436811Y114764D02*
X432249Y119326D01*
Y146177D01*
X405715Y172711D01*
Y328487D01*
X424100Y346872D01*
Y487980D01*
X406521Y505559D01*
Y509660D01*
X406390Y509791D01*
Y514797D01*
X406521Y514928D01*
Y672763D01*
X417721Y683963D01*
Y1006028D01*
X429613Y1017920D01*
G01X436811Y120276D02*
X434417Y122670D01*
Y146718D01*
X407340Y173795D01*
Y327813D01*
X426000Y346473D01*
Y488380D01*
X408146Y506234D01*
Y510334D01*
X408015Y510465D01*
Y514123D01*
X408146Y514254D01*
Y672089D01*
X419346Y683289D01*
Y1001791D01*
X432657Y1015102D01*
G01X443898Y110827D02*
X439376Y115349D01*
Y145260D01*
X409815Y174821D01*
Y326787D01*
X428500Y345472D01*
Y489381D01*
X410621Y507260D01*
Y511360D01*
X410490Y511491D01*
Y513097D01*
X410621Y513228D01*
Y671063D01*
X424012Y684454D01*
Y708220D01*
X421821Y710411D01*
Y901939D01*
X435082Y915200D01*
G01X429724Y116339D02*
X426637Y119426D01*
Y149490D01*
X404090Y172037D01*
Y329161D01*
X421700Y346771D01*
Y450200D01*
G01X408672Y1008038D02*
Y901040D01*
X411221Y898491D01*
Y744259D01*
X393862Y726900D01*
Y719917D01*
G01X412300Y1326200D02*
Y1258700D01*
X386049Y1232449D01*
Y1186065D01*
X379540Y1179556D01*
Y1134816D01*
X391100Y1123256D01*
Y1069300D01*
X412846Y1047554D01*
Y739969D01*
X398677Y725800D01*
Y709385D01*
G01X388788Y749479D02*
X409596Y770287D01*
Y897004D01*
X402150Y904450D01*
Y1053738D01*
X388888Y1067000D01*
Y1118173D01*
G01X393679Y1157480D02*
Y1073521D01*
X413000Y1054200D01*
G01X383191Y1170203D02*
X388416Y1175428D01*
Y1183751D01*
X396135Y1191470D01*
Y1239423D01*
X415422Y1258710D01*
Y1352000D01*
G01X398527Y1188659D02*
Y1233336D01*
G01X450984Y106103D02*
X453650Y108769D01*
Y146703D01*
X420404Y179949D01*
Y253816D01*
X420362Y253858D01*
Y255464D01*
X420404Y255506D01*
Y322326D01*
X452800Y354722D01*
Y420912D01*
G01X443898Y96654D02*
Y97202D01*
X446468Y99772D01*
Y123869D01*
X444703Y125634D01*
Y148352D01*
X414900Y178155D01*
Y324870D01*
X447533Y357503D01*
Y475900D01*
G01X458071Y102166D02*
X454933Y105304D01*
Y107400D01*
X455525Y107992D01*
Y129578D01*
X455494Y129609D01*
Y147189D01*
X425178Y177505D01*
Y218816D01*
X425136Y218858D01*
Y220464D01*
X425178Y220506D01*
Y323093D01*
X456190Y354105D01*
G01X443898Y116339D02*
X441282Y118955D01*
Y127174D01*
X441851Y127743D01*
Y146286D01*
X412290Y175847D01*
Y325761D01*
X433300Y346771D01*
Y488700D01*
X414366Y507634D01*
Y513097D01*
X413231Y514232D01*
Y669556D01*
X426487Y682812D01*
Y709246D01*
X424296Y711437D01*
Y900913D01*
X437558Y914175D01*
Y917758D01*
X437600Y917800D01*
G01X465157Y106103D02*
X462544Y108716D01*
Y125530D01*
X461884Y126190D01*
Y151416D01*
X434817Y178483D01*
Y320389D01*
X462133Y347705D01*
Y473300D01*
G01X465157Y100591D02*
X460669Y105079D01*
Y123290D01*
X459409Y124550D01*
Y150199D01*
X429678Y179930D01*
Y218816D01*
X429636Y218858D01*
Y220464D01*
X429678Y220506D01*
Y320998D01*
X458669Y349989D01*
Y470690D01*
X458679Y470700D01*
G01X450984Y120276D02*
X448611Y122649D01*
Y148089D01*
X417887Y178813D01*
Y324356D01*
X450325Y356794D01*
Y421938D01*
X450500Y422113D01*
Y459562D01*
G01X472244Y96654D02*
X467823Y101075D01*
Y126183D01*
X466267Y127739D01*
Y150631D01*
X439150Y177748D01*
Y286352D01*
X441645Y288847D01*
G01X472244Y102166D02*
X469698Y104712D01*
Y126960D01*
X469667Y126991D01*
Y150732D01*
X441645Y178754D01*
Y284647D01*
G01X479331Y106103D02*
X476100Y109334D01*
Y138362D01*
X473808Y140654D01*
Y152192D01*
X444347Y181653D01*
Y230193D01*
X448012Y233858D01*
Y247964D01*
X444347Y251629D01*
Y310947D01*
X481533Y348133D01*
Y480875D01*
G01X420182Y527432D02*
Y655494D01*
X440371Y675683D01*
Y701683D01*
X426771Y715283D01*
Y898829D01*
X440800Y912858D01*
Y922200D01*
X437750Y925250D01*
Y1126601D01*
X443000Y1131851D01*
Y1160700D01*
X416870Y1186830D01*
Y1221770D01*
X416900Y1221800D01*
G01X434409Y527436D02*
X422331Y539514D01*
Y654531D01*
X442571Y674771D01*
Y700771D01*
X441996Y701346D01*
Y702357D01*
X428396Y715957D01*
Y896109D01*
X443000Y910713D01*
Y964100D01*
X439950Y967150D01*
Y1102438D01*
X444176Y1106664D01*
Y1129915D01*
X446200Y1131939D01*
Y1164600D01*
X441400Y1169400D01*
G01X445582Y925352D02*
X444625Y924395D01*
Y910039D01*
X430626Y896040D01*
Y725763D01*
X473200Y683189D01*
Y646883D01*
X457853Y631536D01*
Y622091D01*
G01X462200Y173109D02*
X464773Y175682D01*
Y328632D01*
X483733Y347592D01*
Y484267D01*
X467647Y500353D01*
Y628610D01*
X476605Y637568D01*
Y683943D01*
X433421Y727127D01*
Y896536D01*
X448952Y912067D01*
Y967572D01*
X449137Y967757D01*
G01X509996Y716996D02*
X508300Y718692D01*
Y740359D01*
X436850Y811809D01*
Y896249D01*
X452853Y912252D01*
Y1005853D01*
X465200Y1018200D01*
G01X512884Y749732D02*
X501226D01*
X438475Y812483D01*
Y895472D01*
X455050Y912047D01*
Y995289D01*
X509037Y1049276D01*
Y1136700D01*
G01X442473Y1068726D02*
Y998427D01*
X442600Y998300D01*
G01X528937Y110827D02*
X533300Y115190D01*
Y127424D01*
X534001Y128125D01*
Y171126D01*
X532916Y172211D01*
Y331593D01*
X506363Y358146D01*
Y478971D01*
X506364Y478972D01*
Y491500D01*
X490265Y507599D01*
Y580388D01*
X498785Y588908D01*
Y622892D01*
X531197Y655304D01*
Y683412D01*
X575556Y727771D01*
Y754925D01*
X585414Y764783D01*
Y905661D01*
X552894Y938181D01*
Y1039393D01*
X555414Y1041913D01*
Y1042209D01*
X556022Y1042817D01*
G01X528937Y116339D02*
X531175Y118577D01*
Y121597D01*
X530168Y122604D01*
Y330840D01*
X503888Y357120D01*
Y479997D01*
X503889Y479998D01*
Y490474D01*
X487660Y506703D01*
Y581284D01*
X496310Y589934D01*
Y623918D01*
X528722Y656330D01*
Y685002D01*
X573081Y729361D01*
Y755951D01*
X582939Y765809D01*
Y903431D01*
X550194Y936176D01*
Y1040194D01*
X552436Y1042436D01*
Y1042494D01*
G01X528937Y96654D02*
X524421Y101170D01*
Y171361D01*
X525218Y172158D01*
Y328306D01*
X498938Y354586D01*
Y482049D01*
X498939Y482050D01*
Y488422D01*
X482710Y504651D01*
Y594508D01*
X491360Y603158D01*
Y629215D01*
X496443Y634298D01*
Y646426D01*
X523772Y673755D01*
Y691682D01*
X567413Y735323D01*
Y759518D01*
X577989Y770094D01*
Y901219D01*
X542650Y936558D01*
Y1123068D01*
X541874Y1123844D01*
Y1233500D01*
X541875Y1233501D01*
Y1235551D01*
X528985Y1248441D01*
Y1339084D01*
X529476Y1339575D01*
Y1351441D01*
X536000Y1357965D01*
Y1359826D01*
G01X528937Y102166D02*
X526296Y104807D01*
Y122505D01*
X527693Y123902D01*
Y329814D01*
X501413Y356094D01*
Y481023D01*
X501414Y481024D01*
Y489448D01*
X485185Y505677D01*
Y593482D01*
X493835Y602132D01*
Y624944D01*
X526247Y657356D01*
Y690656D01*
X570606Y735015D01*
Y756977D01*
X580464Y766835D01*
Y902405D01*
X547719Y935150D01*
Y977088D01*
X547600Y977207D01*
Y1051900D01*
X546700Y1052800D01*
Y1110600D01*
X548725Y1112625D01*
Y1125976D01*
X548300Y1126401D01*
Y1232627D01*
X531460Y1249467D01*
Y1338058D01*
X531951Y1338549D01*
Y1350415D01*
X541362Y1359826D01*
G01X510700Y277200D02*
Y329702D01*
X491150Y349252D01*
Y351399D01*
X491149Y351400D01*
Y485337D01*
X475022Y501464D01*
Y628239D01*
X489018Y642235D01*
Y649504D01*
X513001Y673487D01*
Y711601D01*
X518289Y716889D01*
Y723196D01*
X562912Y767819D01*
Y899290D01*
X530799Y931403D01*
Y952511D01*
X530800Y952512D01*
Y1028300D01*
G01X521850Y106103D02*
X519304Y108649D01*
Y127466D01*
X520494Y128656D01*
Y170935D01*
X522743Y173184D01*
Y327280D01*
X496462Y353561D01*
Y483074D01*
X496464Y483076D01*
Y487396D01*
X480235Y503625D01*
Y589301D01*
X479972Y589564D01*
Y595271D01*
X488885Y604184D01*
Y630241D01*
X493968Y635324D01*
Y647452D01*
X521297Y674781D01*
Y692708D01*
X564938Y736349D01*
Y760544D01*
X575514Y771120D01*
Y899583D01*
X540175Y934922D01*
Y956912D01*
X540174Y956913D01*
Y958963D01*
X540175Y958964D01*
Y1122042D01*
X539399Y1122818D01*
Y1234526D01*
X526510Y1247415D01*
Y1340110D01*
X527000Y1340600D01*
G01X521850Y100591D02*
X517429Y105012D01*
Y245759D01*
X520268Y248598D01*
Y324107D01*
X493988Y350387D01*
Y352534D01*
X493987Y352535D01*
Y484100D01*
X493989Y484102D01*
Y486370D01*
X477760Y502599D01*
Y588275D01*
X477497Y588538D01*
Y622354D01*
X491493Y636350D01*
Y648478D01*
X518822Y675807D01*
Y693734D01*
X562463Y737375D01*
Y761570D01*
X573039Y772146D01*
Y897440D01*
X537700Y932779D01*
Y955886D01*
X537698Y955888D01*
Y957938D01*
X537699Y957939D01*
Y959989D01*
X537700Y959990D01*
Y1121016D01*
X532670Y1126046D01*
Y1152862D01*
X535200Y1155392D01*
Y1235224D01*
X524035Y1246389D01*
Y1340265D01*
X521500Y1342800D01*
G01X557283Y96654D02*
X561792Y101163D01*
Y179961D01*
X545817Y195936D01*
Y337003D01*
X526794Y356026D01*
Y498365D01*
X515057Y510102D01*
Y516184D01*
X506195Y525046D01*
Y585071D01*
X506736Y585612D01*
Y619596D01*
X539149Y652009D01*
Y679459D01*
X583914Y724224D01*
Y750786D01*
X593076Y759948D01*
Y760442D01*
X593365Y760731D01*
Y877358D01*
G01X557283Y102166D02*
X559917Y104800D01*
Y123526D01*
X557823Y125620D01*
Y180429D01*
X543342Y194910D01*
Y335977D01*
X522212Y357107D01*
Y498186D01*
X510600Y509798D01*
Y514106D01*
X510276Y514430D01*
X510201D01*
X503720Y520911D01*
Y586097D01*
X504261Y586638D01*
Y620622D01*
X536674Y653035D01*
Y678433D01*
X536673Y678434D01*
Y680484D01*
X581439Y725250D01*
Y752306D01*
X590890Y761757D01*
Y880576D01*
X592614Y882300D01*
G01X497351Y531531D02*
X498548Y530334D01*
Y512333D01*
X517262Y493619D01*
Y354993D01*
X538392Y333863D01*
Y185886D01*
X539584Y184694D01*
G01X501023Y534941D02*
Y513359D01*
X519737Y494645D01*
Y356081D01*
X540867Y334951D01*
Y188831D01*
X542155Y187543D01*
G01X506500Y1051900D02*
Y1100700D01*
X502300Y1104900D01*
Y1131199D01*
X505874Y1134773D01*
G01X557283Y110827D02*
X552754Y115356D01*
Y125993D01*
X551451Y127296D01*
Y172827D01*
X539584Y184694D01*
G01X557283Y116339D02*
X554707Y118915D01*
Y174991D01*
X542155Y187543D01*
G01X553279Y523331D02*
X553742Y522868D01*
Y515609D01*
X555217Y514134D01*
Y512528D01*
X553742Y511053D01*
Y267705D01*
G01X518700Y548700D02*
X520734Y546666D01*
Y525666D01*
X530400Y516000D01*
Y506600D01*
X534905Y502095D01*
Y489845D01*
X536288Y488462D01*
Y486856D01*
X534905Y485473D01*
Y354105D01*
G01X592400Y1214456D02*
X598024Y1208832D01*
Y1081224D01*
X595500Y1078700D01*
Y1078031D01*
X595812Y1077718D01*
X595840Y1077690D01*
Y759211D01*
X590349Y753720D01*
Y726971D01*
X541887Y678509D01*
Y651246D01*
X509211Y618570D01*
Y573963D01*
X514500Y568674D01*
Y524469D01*
G01X528727Y524973D02*
X522713Y530987D01*
Y563437D01*
X510836Y575314D01*
Y617896D01*
X544087Y651147D01*
Y677116D01*
X597465Y730494D01*
Y1077072D01*
X600640Y1080247D01*
Y1171000D01*
G01X522773Y709638D02*
Y725381D01*
X566931Y769539D01*
Y900047D01*
X532999Y933979D01*
Y1121844D01*
X529680Y1125163D01*
Y1158666D01*
X532200Y1161186D01*
Y1233700D01*
X520600Y1245300D01*
Y1324100D01*
G01X524828Y1159231D02*
X529015Y1163418D01*
Y1233773D01*
X518399Y1244389D01*
Y1359998D01*
X518397Y1360000D01*
G01X522867Y1231097D02*
Y1190284D01*
G01X612000Y502300D02*
X599711Y490011D01*
Y423570D01*
X576844Y400703D01*
Y215400D01*
X566271Y204827D01*
Y167387D01*
G01X592767Y179277D02*
X594200Y180710D01*
Y276862D01*
X667874Y350536D01*
Y489863D01*
X713000Y534989D01*
Y627506D01*
X705984Y634522D01*
X695500D01*
X689500Y640522D01*
Y671000D01*
X665700Y694800D01*
Y773800D01*
X677400Y785500D01*
Y944739D01*
X677457Y944796D01*
G01X592387Y629417D02*
X589800Y632004D01*
Y643900D01*
X591500Y645600D01*
Y661700D01*
X634400Y704600D01*
Y736900D01*
X639518Y742018D01*
Y770363D01*
X659800Y790645D01*
Y928874D01*
X658574Y930100D01*
G01X592387Y1082173D02*
X571300Y1061086D01*
Y1000200D01*
X571400Y1000100D01*
G01X682200Y1026500D02*
Y681300D01*
X691500Y672000D01*
Y641147D01*
X696500Y636147D01*
X706658D01*
X715200Y627605D01*
Y534077D01*
X670074Y488951D01*
Y347642D01*
X642287Y319855D01*
Y266461D01*
G01X627632Y1217300D02*
X625874Y1215542D01*
Y1157531D01*
X637700Y1145705D01*
Y1056512D01*
X669600Y1024612D01*
Y789500D01*
X659299Y779199D01*
Y777377D01*
X659300Y777376D01*
Y678700D01*
X681500Y656500D01*
Y639492D01*
X689720Y631272D01*
X704636D01*
X708600Y627308D01*
Y536813D01*
X695887Y524100D01*
X629963D01*
X627863Y522000D01*
G01X642509Y520667D02*
X695566D01*
X710800Y535901D01*
Y627407D01*
X705310Y632897D01*
X690394D01*
X683500Y639791D01*
Y657500D01*
X661500Y679500D01*
Y778288D01*
X671800Y788588D01*
Y1025524D01*
X639900Y1057424D01*
Y1147378D01*
X636806Y1150472D01*
Y1167861D01*
X636803Y1167864D01*
G01X642287Y719817D02*
Y770020D01*
X662000Y789733D01*
Y1016500D01*
X663800Y1018300D01*
G01X647207Y709555D02*
Y771828D01*
X664200Y788821D01*
Y918800D01*
X667400Y922000D01*
Y1023700D01*
X634803Y1056297D01*
Y1145490D01*
X623661Y1156632D01*
Y1218062D01*
X664000Y1258401D01*
Y1278100D01*
G01X637318Y749649D02*
Y771275D01*
X657600Y791557D01*
Y924850D01*
X650800Y931650D01*
Y1015400D01*
X632603Y1033597D01*
Y1136225D01*
G01X645200Y1067800D02*
Y1154560D01*
X642942Y1156818D01*
G01X647716Y1154150D02*
Y1170284D01*
X642500Y1175500D01*
Y1206500D01*
X673000Y1237000D01*
Y1354100D01*
G01X647126Y1189513D02*
X717674Y1260061D01*
Y1293834D01*
X774790Y1350950D01*
X777550D01*
X795818Y1369218D01*
Y1468694D01*
X796848Y1469724D01*
G01X705348Y478425D02*
X705399Y478374D01*
Y320040D01*
X696729Y311370D01*
Y212552D01*
X692477Y208300D01*
Y104968D01*
X690807Y103298D01*
G01X716600Y1081973D02*
Y1064785D01*
X674300Y1022485D01*
Y1001620D01*
G01X757020Y159692D02*
X753006Y163706D01*
Y195103D01*
X750556Y197553D01*
X747242D01*
G01X717188Y176461D02*
X714200Y179449D01*
Y188596D01*
X740911Y215307D01*
Y593296D01*
X741438Y593823D01*
Y595429D01*
X740911Y595956D01*
Y738212D01*
X742225Y739526D01*
Y756225D01*
X780800Y794800D01*
Y959300D01*
G01X716600Y629417D02*
X720952Y633769D01*
Y636760D01*
X715700Y642012D01*
Y715300D01*
X740600Y740200D01*
Y757712D01*
X776400Y793512D01*
Y956500D01*
G01X728174Y1275611D02*
Y1291882D01*
X778441Y1342149D01*
X781197D01*
X804618Y1365570D01*
Y1462325D01*
X806568Y1464275D01*
G01X725678Y1272799D02*
X725765Y1272886D01*
Y1292586D01*
X777528Y1344349D01*
X780285D01*
X802418Y1366482D01*
Y1461604D01*
X802433Y1461619D01*
G01X722790Y1270557D02*
Y1292724D01*
X776615Y1346549D01*
X779373D01*
X800218Y1367394D01*
Y1464552D01*
X800900Y1465234D01*
G01X720446Y1267427D02*
Y1293493D01*
X775702Y1348749D01*
X778461D01*
X798018Y1368306D01*
Y1466787D01*
X800462Y1469231D01*
G01X731500Y1277811D02*
Y1292095D01*
X779354Y1339949D01*
X782109D01*
X806800Y1364640D01*
Y1460344D01*
X806952Y1460496D01*
G01X784000Y1024000D02*
Y794700D01*
X749550Y760250D01*
Y668250D01*
X755813Y661987D01*
Y171343D01*
X758619Y168537D01*
G01X763188Y172500D02*
X767152D01*
X773789Y179137D01*
Y211819D01*
X761119Y224489D01*
Y336873D01*
X789739Y365493D01*
G01X754500Y668741D02*
X758500Y672741D01*
Y765800D01*
X786800Y794100D01*
Y1016000D01*
G01X752500Y1167500D02*
Y1063100D01*
X759500Y1056100D01*
G01X829921Y-458D02*
Y31188D01*
X824067Y37042D01*
Y211908D01*
X844285Y232126D01*
Y280045D01*
X844327Y280087D01*
Y286370D01*
X828368Y302329D01*
Y569574D01*
X839867Y581073D01*
Y765537D01*
X808242Y797162D01*
Y1096454D01*
X782606Y1122090D01*
Y1208240D01*
X784544Y1210178D01*
G01Y1205978D02*
Y1123264D01*
X810442Y1097366D01*
Y798074D01*
X842067Y766449D01*
Y580161D01*
X830568Y568662D01*
Y303241D01*
X847068Y286741D01*
Y230973D01*
X825699Y209604D01*
Y40257D01*
X835775Y30181D01*
Y-1285D01*
X833714Y-3346D01*
X833724D01*
G01X779535Y1193469D02*
X774008Y1187942D01*
Y1119866D01*
X774021Y1119853D01*
Y1119040D01*
X774422Y1118639D01*
Y1117826D01*
X799442Y1092806D01*
Y793514D01*
X831067Y761889D01*
Y584721D01*
X818860Y572514D01*
Y299389D01*
X835626Y282623D01*
Y235714D01*
X816218Y216306D01*
Y52308D01*
X806299Y42389D01*
Y35967D01*
X806314Y35952D01*
G01X806299Y-458D02*
X811533Y4776D01*
Y44486D01*
X818073Y51026D01*
Y215537D01*
X837481Y234945D01*
Y239376D01*
X837251Y239606D01*
Y284110D01*
X821768Y299593D01*
Y572310D01*
X833267Y583809D01*
Y762801D01*
X801642Y794426D01*
Y1093718D01*
X775646Y1119714D01*
Y1120527D01*
X775633Y1120540D01*
Y1185367D01*
X779535Y1189269D01*
G01X814173Y-458D02*
Y32146D01*
X820238Y38211D01*
Y214640D01*
X839646Y234048D01*
Y284827D01*
X823968Y300505D01*
Y571398D01*
X835467Y582897D01*
Y763713D01*
X803842Y795338D01*
Y1094630D01*
X777258Y1121214D01*
Y1182392D01*
X779535Y1184669D01*
G01X822047Y-458D02*
X822150Y-355D01*
Y213848D01*
X841558Y233256D01*
Y286027D01*
X826168Y301417D01*
Y570486D01*
X837667Y581985D01*
Y764625D01*
X806042Y796250D01*
Y1095542D01*
X779535Y1122049D01*
Y1180469D01*
G01X797177Y1189537D02*
X794524Y1186884D01*
Y1130207D01*
X821442Y1103289D01*
Y802634D01*
X853067Y771009D01*
Y574740D01*
X847338Y569011D01*
Y488422D01*
X838693Y479777D01*
Y319426D01*
X858158Y299961D01*
Y278192D01*
X868696Y267654D01*
Y250014D01*
X868796Y249914D01*
Y224999D01*
X836635Y192838D01*
Y54882D01*
X849432Y42085D01*
Y35552D01*
X884915Y69D01*
X886322D01*
G01X797225Y1185337D02*
Y1130618D01*
X823642Y1104201D01*
Y803546D01*
X855267Y771921D01*
Y573828D01*
X848963Y567524D01*
Y487093D01*
X840402Y478532D01*
Y322017D01*
X860208Y302211D01*
Y279507D01*
X870321Y269394D01*
Y250688D01*
X870421Y250588D01*
Y224325D01*
X838383Y192287D01*
Y55697D01*
X851057Y43023D01*
Y37364D01*
X884619Y3802D01*
X886427D01*
G01X842470Y41295D02*
X831057Y52708D01*
Y194157D01*
X863921Y227021D01*
Y247892D01*
X863821Y247992D01*
Y261970D01*
X852221Y273570D01*
Y291672D01*
X833818Y310075D01*
Y565688D01*
X846467Y578337D01*
Y768273D01*
X814842Y799898D01*
Y1100553D01*
X789049Y1126346D01*
Y1127159D01*
X788592Y1127616D01*
Y1174990D01*
X792263Y1178661D01*
G01X845661Y-3642D02*
X842328D01*
X838251Y435D01*
Y31036D01*
X829432Y39855D01*
Y194831D01*
X862296Y227695D01*
Y247218D01*
X862196Y247318D01*
Y261296D01*
X850596Y272896D01*
Y288823D01*
X832193Y307226D01*
Y567175D01*
X844267Y579249D01*
Y767361D01*
X812642Y798986D01*
Y1099641D01*
X786935Y1125348D01*
Y1177533D01*
X792263Y1182861D01*
G01Y1174461D02*
X790217Y1172415D01*
Y1128290D01*
X817042Y1101465D01*
Y800810D01*
X848667Y769185D01*
Y576564D01*
X844088Y571985D01*
Y489770D01*
X835443Y481125D01*
Y311562D01*
X853846Y293159D01*
Y274351D01*
X865446Y262751D01*
Y248666D01*
X865546Y248566D01*
Y226347D01*
X833096Y193897D01*
Y53766D01*
X846182Y40680D01*
Y33549D01*
X886418Y-6687D01*
Y-7350D01*
G01X792263Y1170261D02*
Y1129356D01*
X819242Y1102377D01*
Y801722D01*
X850867Y770097D01*
Y575652D01*
X845713Y570498D01*
Y489096D01*
X837068Y480451D01*
Y315572D01*
X855545Y297095D01*
Y278192D01*
X867071Y266666D01*
Y249340D01*
X867171Y249240D01*
Y225673D01*
X834944Y193446D01*
Y54267D01*
X847807Y41404D01*
Y34359D01*
X885901Y-3735D01*
X886351D01*
G01X1149984Y1115804D02*
Y1109516D01*
X1177019Y1082481D01*
Y1074881D01*
X1227350Y1024550D01*
Y508524D01*
X1164830Y446004D01*
Y238142D01*
X1169999Y232973D01*
Y117021D01*
X1170153D01*
Y-103798D01*
X1143165Y-130786D01*
X926762D01*
X875356Y-79380D01*
Y-13819D01*
X863142Y-1605D01*
X842705D01*
X841104Y-4D01*
Y36025D01*
X841733Y36654D01*
G01X1143550Y1120317D02*
Y1092790D01*
X1216350Y1019990D01*
Y513084D01*
X1156705Y453439D01*
Y232333D01*
X1158999Y230039D01*
Y121581D01*
X1159153D01*
Y-99238D01*
X1135730Y-122661D01*
X930184D01*
X883864Y-76341D01*
Y-6589D01*
X872868Y4407D01*
X847340D01*
X843463Y530D01*
G01X803438Y1139700D02*
Y1131302D01*
X831286Y1103454D01*
Y805269D01*
X863746Y772809D01*
Y566344D01*
X851701Y554299D01*
Y486330D01*
X842877Y477506D01*
Y351123D01*
X847334Y346666D01*
Y320020D01*
X862684Y304670D01*
Y280532D01*
X872796Y270420D01*
Y251714D01*
G01X952200Y742600D02*
X912216D01*
X842588Y812228D01*
Y1242882D01*
X815500Y1269970D01*
Y1576631D01*
X829387Y1590518D01*
Y1627812D01*
X833859Y1632284D01*
G01X957100Y742900D02*
X954575Y745425D01*
X912892D01*
X845063Y813254D01*
Y1243908D01*
X818015Y1270956D01*
Y1575645D01*
X831262Y1588892D01*
Y1624175D01*
X833859Y1626772D01*
G01X826772Y1650394D02*
X809953Y1633575D01*
Y1269717D01*
X838488Y1241182D01*
Y808012D01*
X909800Y736700D01*
X953200D01*
G01X956900Y737600D02*
X954638Y739862D01*
X911081D01*
X840113Y810830D01*
Y1241856D01*
X812953Y1269016D01*
Y1631063D01*
X826772Y1644882D01*
G01X949048Y755225D02*
X948948Y755325D01*
X917395D01*
X854963Y817757D01*
Y1248012D01*
X827915Y1275060D01*
Y1566217D01*
X850815Y1589117D01*
Y1617745D01*
X855118Y1622048D01*
G01X952476Y753652D02*
Y756529D01*
X951105Y757900D01*
X918321D01*
X857438Y818783D01*
Y1249038D01*
X830390Y1276086D01*
Y1561790D01*
X852690Y1584090D01*
Y1614108D01*
X855118Y1616536D01*
G01X951300Y747900D02*
X913918D01*
X847538Y814280D01*
Y1244934D01*
X820490Y1271982D01*
Y1571590D01*
X836434Y1587534D01*
Y1645883D01*
X840945Y1650394D01*
G01X956200Y748200D02*
X954025Y750375D01*
X914944D01*
X850013Y815306D01*
Y1245960D01*
X822965Y1273008D01*
Y1568269D01*
X838309Y1583613D01*
Y1642246D01*
X840945Y1644882D01*
G01X942000Y752850D02*
X915970D01*
X852488Y816332D01*
Y1246986D01*
X825440Y1274034D01*
Y1567243D01*
X844700Y1586503D01*
Y1615300D01*
X847511Y1618111D01*
X848032D01*
G01X869292Y1622048D02*
X866813Y1619569D01*
Y1586937D01*
X837229Y1557353D01*
Y1534489D01*
X837449Y1534269D01*
Y1532217D01*
X837229Y1531997D01*
Y1276249D01*
X862388Y1251090D01*
Y857669D01*
X872101Y847956D01*
Y846350D01*
X872100Y846349D01*
Y836957D01*
X872101Y836956D01*
Y835350D01*
X872100Y835349D01*
Y820600D01*
X929159Y763541D01*
X947866D01*
G01X869292Y1616536D02*
X872041Y1613787D01*
Y1588664D01*
X839704Y1556327D01*
Y1537779D01*
X841352Y1536131D01*
Y1519960D01*
X839704Y1518312D01*
Y1277275D01*
X864863Y1252116D01*
Y859137D01*
X876500Y847500D01*
Y820000D01*
X929000Y767500D01*
X950965D01*
X952234Y766231D01*
X957629D01*
G01X944500Y760750D02*
X918972D01*
X859913Y819809D01*
Y1250064D01*
X833745Y1276232D01*
Y1526958D01*
X832865Y1527838D01*
Y1531591D01*
X834517Y1533243D01*
X834974D01*
G01X1152880Y1097672D02*
X1173389Y1077163D01*
Y1072287D01*
X1222950Y1022726D01*
Y510348D01*
X1161580Y448978D01*
Y236794D01*
X1165599Y232775D01*
Y118845D01*
X1165753D01*
Y-101974D01*
X1140191Y-127536D01*
X928162D01*
X902715Y-102089D01*
X902663D01*
X878688Y-78114D01*
Y-11215D01*
X867080Y393D01*
G01X1152682Y1091138D02*
Y1086770D01*
X1218550Y1020902D01*
Y512172D01*
X1158330Y451952D01*
Y233820D01*
X1161199Y230951D01*
Y120669D01*
X1161353D01*
Y-100150D01*
X1137217Y-124286D01*
X929510D01*
X882190Y-76966D01*
Y-8011D01*
X873892Y287D01*
G01X1139524Y1121817D02*
X1140364Y1122657D01*
X1144843D01*
X1145875Y1121625D01*
Y1100686D01*
X1171764Y1074797D01*
Y1071613D01*
X1220750Y1022627D01*
Y511260D01*
X1159955Y450465D01*
Y235307D01*
X1163399Y231863D01*
Y119757D01*
X1163553D01*
Y-101062D01*
X1138704Y-125911D01*
X928836D01*
X903389Y-100464D01*
X903337D01*
X880481Y-77608D01*
Y-9804D01*
X867979Y2698D01*
X851533D01*
X849484Y649D01*
G01X1137436Y1124750D02*
X1146250D01*
X1147500Y1123500D01*
Y1106000D01*
X1175054Y1078446D01*
Y1073734D01*
X1225150Y1023638D01*
Y509436D01*
X1163205Y447491D01*
Y237468D01*
X1167799Y232874D01*
Y117933D01*
X1167953D01*
Y-102886D01*
X1141678Y-129161D01*
X927436D01*
X877022Y-78747D01*
Y-13051D01*
X863312Y659D01*
X857513D01*
G01X885448Y37380D02*
Y44362D01*
X891239Y50153D01*
Y85261D01*
X881549Y94951D01*
Y326304D01*
G01X897638Y1608268D02*
Y1608038D01*
X893130Y1603530D01*
Y1585428D01*
X858687Y1550985D01*
Y1519293D01*
X852430Y1513036D01*
Y1282552D01*
X877368Y1257614D01*
Y1257613D01*
X877589Y1257392D01*
Y877973D01*
X891289Y864273D01*
Y857730D01*
X891089Y857530D01*
Y855924D01*
X891289Y855724D01*
Y838289D01*
X891200Y838200D01*
G01X890552Y1607874D02*
X886338Y1603660D01*
Y1583655D01*
X853489Y1550806D01*
Y1540393D01*
X850828Y1537732D01*
Y1516032D01*
X849180Y1514384D01*
Y1281204D01*
X874118Y1256266D01*
Y1256265D01*
X874339Y1256044D01*
Y875861D01*
X882988Y867212D01*
Y854543D01*
X886989Y850542D01*
Y844958D01*
X886988Y844957D01*
Y830385D01*
X940135Y777238D01*
X957462D01*
X973500Y761200D01*
Y643700D01*
X994424Y622776D01*
Y540817D01*
X983308Y529701D01*
Y372075D01*
X1002180Y353203D01*
Y105500D01*
X1000143Y103463D01*
Y43477D01*
X1002180Y41440D01*
Y-30292D01*
X994923Y-37549D01*
Y-54859D01*
X989050Y-60732D01*
Y-70850D01*
G01X897638Y1603937D02*
X895025Y1601324D01*
Y1584887D01*
X860312Y1550174D01*
Y1518619D01*
X854055Y1512362D01*
Y1283226D01*
X878993Y1258288D01*
Y1258287D01*
X879214Y1258066D01*
Y878677D01*
X894965Y862926D01*
Y843500D01*
G01X897638Y1598425D02*
X899876Y1596187D01*
Y1587006D01*
X861937Y1549067D01*
Y1517945D01*
X858523Y1514531D01*
Y1501704D01*
X860561Y1499666D01*
Y1493529D01*
X862117Y1491973D01*
Y1490367D01*
X860561Y1488811D01*
Y1286776D01*
X884523Y1262814D01*
Y878404D01*
X896938Y865989D01*
Y839062D01*
X897000Y839000D01*
G01X890552Y1602363D02*
X888213Y1600024D01*
Y1583231D01*
X857062Y1552080D01*
Y1519967D01*
X850805Y1513710D01*
Y1281878D01*
X875743Y1256940D01*
Y1256939D01*
X875964Y1256718D01*
Y877299D01*
X888962Y864301D01*
Y843262D01*
G01X860179Y1491170D02*
X856524Y1487515D01*
Y1286851D01*
X882349Y1261026D01*
Y896336D01*
X882333Y896320D01*
G01X904725Y1630709D02*
X902033Y1628017D01*
Y1586102D01*
X893000Y1577069D01*
Y1570650D01*
X896240Y1567410D01*
Y1543648D01*
X897800Y1542088D01*
Y1490853D01*
X891505Y1484558D01*
Y1451247D01*
X900257Y1442495D01*
Y1409357D01*
X896200Y1405300D01*
G01X897038Y1577600D02*
X895200Y1575762D01*
Y1572890D01*
X898610Y1569480D01*
Y1544390D01*
X903977Y1539023D01*
Y1493918D01*
X893705Y1483646D01*
Y1452159D01*
X902457Y1443407D01*
Y1407957D01*
X896100Y1401600D01*
G01X964537Y1160310D02*
X954190D01*
X910081Y1204419D01*
Y1395981D01*
X913457Y1399357D01*
Y1452031D01*
X906600Y1458888D01*
Y1461600D01*
G01X958870Y1163617D02*
X954383D01*
X912281Y1205719D01*
Y1395069D01*
X915657Y1398445D01*
Y1452943D01*
X909400Y1459200D01*
G01X962941Y1165929D02*
X955971D01*
X914481Y1207419D01*
Y1394157D01*
X917857Y1397533D01*
Y1457043D01*
X910000Y1464900D01*
G01X967497Y1168802D02*
X956798D01*
X916681Y1208919D01*
Y1393245D01*
X920057Y1396621D01*
Y1457955D01*
X910851Y1467161D01*
X905500D01*
G01X957871Y1171219D02*
X918881Y1210209D01*
Y1392333D01*
X922257Y1395709D01*
Y1463912D01*
X908742Y1477427D01*
G01X963000Y1174427D02*
X960996D01*
X921081Y1214342D01*
Y1391421D01*
X924457Y1394797D01*
Y1465212D01*
X908542Y1481127D01*
G01X904725Y1650394D02*
X907731Y1653400D01*
X913340D01*
X915450Y1651290D01*
Y1545350D01*
X910577Y1540477D01*
Y1491182D01*
X900305Y1480910D01*
Y1454895D01*
X909057Y1446143D01*
Y1403257D01*
X895900Y1390100D01*
G01X924059Y1647700D02*
Y1548734D01*
X912777Y1537452D01*
Y1490270D01*
X902505Y1479998D01*
Y1455807D01*
X911257Y1447055D01*
Y1401057D01*
X896200Y1386000D01*
G01X904725Y1640551D02*
X908377Y1636899D01*
Y1492094D01*
X898105Y1481822D01*
Y1453983D01*
X906857Y1445231D01*
Y1404557D01*
X896100Y1393800D01*
G01X897400Y1574000D02*
X900810Y1570590D01*
Y1545302D01*
X906177Y1539935D01*
Y1493006D01*
X895905Y1482734D01*
Y1453071D01*
X904657Y1444319D01*
Y1406357D01*
X896200Y1397900D01*
G01X1041616Y997225D02*
X1046565Y992276D01*
Y938093D01*
X1069510Y915148D01*
Y825790D01*
X1041498Y797778D01*
Y520264D01*
X1030150Y508916D01*
Y162734D01*
X1051893Y140991D01*
Y82349D01*
X1040936Y71392D01*
Y-15563D01*
X1036493Y-20006D01*
Y-47809D01*
X1032925Y-51377D01*
Y-75378D01*
X996732Y-111571D01*
X985629D01*
X981700Y-115500D01*
G01X1037282Y995028D02*
X1043356Y988954D01*
Y937801D01*
X1067035Y914122D01*
Y826816D01*
X1039023Y798804D01*
Y521739D01*
X1027675Y510391D01*
Y161707D01*
X1048141Y141241D01*
Y83391D01*
X1038028Y73278D01*
Y-14970D01*
X1034018Y-18980D01*
Y-46783D01*
X1030450Y-50351D01*
Y-74352D01*
X995706Y-109096D01*
X983187D01*
X976713Y-115570D01*
G01X1050763Y829163D02*
Y821363D01*
X1030268Y800868D01*
Y523487D01*
X1022725Y515944D01*
Y80748D01*
X1033078Y70395D01*
Y-12918D01*
X1025500Y-20496D01*
Y-72300D01*
X1020400Y-77400D01*
X1006900D01*
X989316Y-94984D01*
G01X972924Y1158033D02*
Y1131094D01*
X991214Y1112804D01*
Y1062808D01*
X963298Y1034892D01*
Y1028998D01*
X961842Y1027542D01*
Y1016045D01*
X958832Y1013035D01*
Y993549D01*
X984050Y968331D01*
Y862050D01*
X985394Y860706D01*
Y831491D01*
X1012413Y804472D01*
Y525191D01*
X1008661Y521439D01*
Y521122D01*
X1007802Y520263D01*
Y103376D01*
X1005619Y101193D01*
Y45747D01*
X1011038Y40328D01*
Y-55762D01*
X998045Y-68755D01*
Y-79300D01*
G01X1119042Y1351595D02*
X1116544Y1349097D01*
X1072696D01*
X979912Y1256313D01*
Y1182572D01*
X980449Y1182035D01*
Y1127070D01*
X993689Y1113830D01*
Y1061782D01*
X965960Y1034053D01*
Y1013815D01*
X963566Y1011421D01*
Y992316D01*
X987869Y968013D01*
Y832517D01*
X1015099Y805287D01*
Y524059D01*
X1010821Y519781D01*
Y102894D01*
X1008094Y100167D01*
Y46773D01*
X1013513Y41354D01*
Y-56887D01*
X1000418Y-69982D01*
G01X1115105Y1344508D02*
Y1343822D01*
X1111612Y1340329D01*
X1070930D01*
X985580Y1254979D01*
Y1128301D01*
X995987Y1117894D01*
Y1060936D01*
X971308Y1036257D01*
Y1014428D01*
X968635Y1011755D01*
Y989546D01*
X989494Y968687D01*
Y833191D01*
X1021706Y800979D01*
Y526373D01*
X1012538Y517205D01*
Y75214D01*
X1015200Y72552D01*
Y-57500D01*
X1019082Y-61382D01*
Y-71000D01*
G01X1119042Y1323249D02*
X1114392Y1327899D01*
X1082449D01*
X1081849Y1328499D01*
X1066042D01*
X1001562Y1264019D01*
Y1197164D01*
X999912Y1195514D01*
Y1150402D01*
X996916Y1147406D01*
Y1122765D01*
X1000087Y1119594D01*
Y1058322D01*
X978433Y1036668D01*
Y998564D01*
X991969Y985028D01*
Y834217D01*
X1024181Y802005D01*
Y524402D01*
X1015300Y515521D01*
Y76624D01*
X1021086Y70838D01*
Y-11682D01*
G01X1119042Y1337422D02*
X1115720Y1334100D01*
X1068057D01*
X987205Y1253248D01*
Y1128975D01*
X997612Y1118568D01*
Y1059348D01*
X975958Y1037694D01*
Y996268D01*
X987734Y984492D01*
Y979575D01*
G01X1011100Y904600D02*
X1018600D01*
X1020549Y906549D01*
Y951649D01*
X1009082Y963116D01*
Y982717D01*
X990632Y1001167D01*
Y1034863D01*
X1006083Y1050314D01*
Y1120600D01*
X1001998Y1124685D01*
Y1145486D01*
X1004862Y1148350D01*
Y1193462D01*
X1006512Y1195112D01*
Y1254796D01*
X1065664Y1313948D01*
X1082226D01*
X1082674Y1313500D01*
X1114617D01*
X1119042Y1309075D01*
G01X1113530Y1323249D02*
X1110755Y1326024D01*
X1067068D01*
X1004037Y1262993D01*
Y1196138D01*
X1002387Y1194488D01*
Y1149376D01*
X999391Y1146380D01*
Y1123791D01*
X1002562Y1120620D01*
Y1057296D01*
X980908Y1035642D01*
Y999590D01*
X999632Y980866D01*
Y830055D01*
X1027793Y801894D01*
Y524513D01*
X1017775Y514495D01*
Y78400D01*
X1026717Y69458D01*
Y-11646D01*
G01X1109593Y1344508D02*
X1106995Y1347106D01*
X1085515D01*
X1082430Y1344021D01*
X1071121D01*
X982387Y1255287D01*
Y1183598D01*
G01X1034271Y876911D02*
X1056800Y854382D01*
Y823583D01*
X1032743Y799526D01*
Y522461D01*
X1025200Y514918D01*
Y82605D01*
X1035553Y72252D01*
Y-13944D01*
X1027975Y-21522D01*
Y-73326D01*
X1021425Y-79876D01*
X1019375D01*
X1019374Y-79875D01*
X1009125D01*
X993816Y-95184D01*
G01X1019118Y-34382D02*
Y-23377D01*
X1030603Y-11892D01*
Y69369D01*
X1020250Y79722D01*
Y357188D01*
G01X1043674Y451921D02*
X1033024Y441271D01*
Y163361D01*
X1054368Y142017D01*
Y81323D01*
X1043411Y70366D01*
Y-16589D01*
X1041062Y-18938D01*
Y-112049D01*
X1041713Y-112700D01*
Y-115465D01*
G01X1043500Y446600D02*
X1046200Y443900D01*
Y429858D01*
X1039500Y423158D01*
Y161058D01*
X1057480Y143078D01*
Y80934D01*
X1045886Y69340D01*
Y-19323D01*
X1043513Y-21696D01*
G01X1050763Y829163D02*
Y855147D01*
X1031690Y874220D01*
Y881291D01*
X1036338Y885939D01*
Y923458D01*
X1033625Y926171D01*
Y987318D01*
X1021276Y999667D01*
Y1021821D01*
X1022592Y1023137D01*
Y1024743D01*
X1022300Y1025035D01*
Y1065559D01*
X1021562Y1066297D01*
Y1067903D01*
X1022963Y1069304D01*
Y1079506D01*
X1026363Y1082906D01*
Y1123903D01*
X1024338Y1125928D01*
Y1139049D01*
X1025940Y1140651D01*
Y1181863D01*
X1017354Y1190449D01*
Y1196124D01*
G01X1034271Y876911D02*
Y880370D01*
X1039248Y885347D01*
Y985196D01*
X1028566Y995878D01*
Y1002551D01*
X1025438Y1005679D01*
Y1078480D01*
X1028838Y1081880D01*
Y1190766D01*
X1021061Y1198543D01*
G01X1113530Y1309075D02*
X1110980Y1311625D01*
X1082378D01*
X1082226Y1311473D01*
X1066690D01*
X1008987Y1253770D01*
Y1147987D01*
X1006762Y1145762D01*
Y1124107D01*
X1008558Y1122311D01*
Y1049288D01*
X993700Y1034430D01*
Y1027400D01*
X996400Y1024700D01*
Y1001400D01*
X1011557Y986243D01*
Y964143D01*
X1025000Y950700D01*
Y897700D01*
G01X1115105Y1301989D02*
X1110642Y1297526D01*
X1082452D01*
X1082226Y1297300D01*
X1062290D01*
X1013937Y1248947D01*
Y1139438D01*
X1014203D01*
X1015338Y1138303D01*
Y1136697D01*
X1014203Y1135562D01*
X1014192D01*
Y1047920D01*
X1007849Y1041577D01*
Y1033743D01*
G01X1109593Y1301989D02*
X1107005Y1299401D01*
X1082600D01*
X1082226Y1299775D01*
X1063316D01*
X1063315Y1299776D01*
X1061265D01*
X1011462Y1249973D01*
Y1048691D01*
X1001171Y1038400D01*
Y1038314D01*
X996600Y1033743D01*
G01X1033000Y1416125D02*
X1041625D01*
X1048500Y1423000D01*
X1098818D01*
X1113530Y1408288D01*
G01X1119042Y1394115D02*
X1118985D01*
X1114500Y1398600D01*
X1090525D01*
X1088400Y1400725D01*
Y1413694D01*
X1082088Y1420006D01*
X1048207D01*
X1039201Y1411000D01*
X1028000D01*
G01X1113530Y1394115D02*
X1110946Y1396699D01*
X1088401D01*
X1085700Y1399400D01*
Y1413742D01*
X1081061Y1418381D01*
X1048881D01*
X1038500Y1408000D01*
X1031500D01*
G01X1043303Y-27685D02*
X1045900Y-30282D01*
Y-72162D01*
X1047738Y-74000D01*
Y-105439D01*
X1051713Y-109414D01*
Y-114887D01*
G01X1045873Y-24660D02*
X1048375Y-27162D01*
Y-71136D01*
X1050213Y-72974D01*
Y-104413D01*
X1056713Y-110913D01*
Y-115413D01*
G01X1074425Y447225D02*
Y439175D01*
X1089425Y424175D01*
Y364026D01*
X1074425Y349026D01*
Y80312D01*
X1069663Y75550D01*
Y-30763D01*
X1076962Y-38062D01*
Y-53525D01*
X1080337Y-56900D01*
Y-109194D01*
X1086713Y-115570D01*
G01X1071950Y453288D02*
Y438148D01*
X1086249Y423849D01*
Y364351D01*
X1071950Y350052D01*
Y81338D01*
X1067188Y76576D01*
Y-37069D01*
X1069803Y-39684D01*
Y-62241D01*
X1077862Y-70300D01*
Y-111718D01*
X1081713Y-115569D01*
Y-115570D01*
G01X1069018Y456900D02*
X1069475Y456443D01*
Y437122D01*
X1083774Y422823D01*
Y366899D01*
X1069475Y352600D01*
Y82364D01*
X1059498Y72387D01*
Y-34998D01*
X1063683Y-39183D01*
Y-103770D01*
X1071713Y-111800D01*
Y-115570D01*
G01X1065985Y460500D02*
X1067000Y459485D01*
Y436096D01*
X1081299Y421797D01*
Y368999D01*
X1067000Y354700D01*
Y83390D01*
X1057023Y73413D01*
Y-60949D01*
X1061067Y-64993D01*
Y-104867D01*
X1066713Y-110513D01*
Y-115570D01*
G01X1079455Y-30742D02*
Y-30677D01*
X1091322D01*
X1132425Y10426D01*
Y174815D01*
X1134110Y176500D01*
G01X1115105Y1016938D02*
X1112043Y1020000D01*
X1088500D01*
X1080500Y1012000D01*
Y951902D01*
X1098057Y934345D01*
Y758612D01*
X1087664Y748219D01*
Y491964D01*
X1052750Y457050D01*
Y432808D01*
X1041500Y421558D01*
Y382858D01*
G01X1119042Y1024025D02*
X1114478Y1028589D01*
X1090087D01*
X1075550Y1014052D01*
Y949850D01*
X1086600Y938800D01*
Y833200D01*
G01X1113530Y1024025D02*
X1110841Y1026714D01*
X1091713D01*
X1078025Y1013026D01*
Y950876D01*
X1089300Y939601D01*
Y836100D01*
G01X1109593Y1188603D02*
X1106196Y1192000D01*
X1088510D01*
X1075600Y1179090D01*
G01X1053743Y1174221D02*
X1054164Y1173800D01*
X1082400D01*
X1093600Y1185000D01*
X1110046D01*
X1113530Y1181516D01*
G01X1046900Y1168000D02*
X1080800D01*
X1090800Y1178000D01*
X1111726D01*
X1115105Y1174621D01*
Y1174430D01*
G01X1109593Y1202776D02*
X1105969Y1206400D01*
X1083800D01*
X1076032Y1198632D01*
Y1191144D01*
G01X1113530Y1195690D02*
X1110120Y1199100D01*
X1091900D01*
X1076900Y1184100D01*
X1070000D01*
G01X1109593Y1287816D02*
X1106177Y1284400D01*
X1087800D01*
X1079500Y1276100D01*
G01X1077300Y1271700D02*
X1082000D01*
X1087400Y1277100D01*
X1109901D01*
X1113530Y1280729D01*
G01X1115105Y1372855D02*
X1110650Y1368400D01*
X1093500D01*
X1082553Y1357453D01*
X1077718D01*
X1044481Y1324216D01*
X1042343D01*
G01X1115105Y1387028D02*
Y1384105D01*
X1113500Y1382500D01*
X1090200D01*
X1075700Y1368000D01*
X1069019D01*
X1051011Y1349992D01*
X1048251D01*
G01X1109593Y1387028D02*
X1109353D01*
X1106725Y1384400D01*
X1089131D01*
X1074731Y1370000D01*
X1068155D01*
X1054481Y1356326D01*
X1046372D01*
G01X1042343Y1337616D02*
X1049280D01*
X1075014Y1363350D01*
X1077650D01*
X1089600Y1375300D01*
X1114400D01*
X1119042Y1379942D01*
G01X1113530D02*
X1113042D01*
X1110400Y1377300D01*
X1088600D01*
X1077100Y1365800D01*
X1074600D01*
X1051468Y1342668D01*
X1042443D01*
G01X1109593Y1372855D02*
Y1372768D01*
X1107125Y1370300D01*
X1091131D01*
X1081016Y1360185D01*
X1074713D01*
X1045444Y1330916D01*
X1042343D01*
G01X1149823Y1233373D02*
X1157637Y1225559D01*
Y1148637D01*
X1119000Y1110000D01*
Y1087900D01*
X1143938Y1062962D01*
Y1002211D01*
X1142142Y1000415D01*
Y184700D01*
X1137100Y179658D01*
Y175900D01*
X1134050Y172850D01*
Y9448D01*
X1091825Y-32777D01*
Y-89175D01*
X1089318Y-91682D01*
G01X1101246Y-31005D02*
Y-28054D01*
X1138500Y9200D01*
Y173500D01*
X1140550Y175550D01*
Y179200D01*
G01X1124024Y-30840D02*
X1143684Y-11180D01*
Y6085D01*
X1144425Y6826D01*
Y173521D01*
X1144738Y173834D01*
Y175440D01*
X1144148Y176030D01*
Y419514D01*
X1145230Y420596D01*
Y1000762D01*
X1153700Y1009232D01*
Y1055800D01*
X1121500Y1088000D01*
Y1094500D01*
X1123400Y1096400D01*
X1123600D01*
G01X1128765Y-34297D02*
X1146348Y-16714D01*
Y173145D01*
X1146363Y173160D01*
Y176114D01*
X1146348Y176129D01*
Y419415D01*
X1146856Y419923D01*
Y420022D01*
X1147430Y420596D01*
Y999850D01*
X1155900Y1008320D01*
Y1056600D01*
X1123838Y1088662D01*
Y1092800D01*
G01X1111254Y-31020D02*
X1111253Y-31019D01*
Y-24047D01*
X1142800Y7500D01*
Y174637D01*
G01X1105328Y-31005D02*
Y-27673D01*
X1140500Y7499D01*
Y171400D01*
G01X1094300Y-60300D02*
Y-51900D01*
X1097033Y-49167D01*
Y-29868D01*
X1136203Y9302D01*
Y167600D01*
G01X1113530Y995678D02*
X1110986Y993134D01*
X1092466D01*
X1088851Y989519D01*
Y970737D01*
X1135410Y924178D01*
Y381990D01*
X1138475Y378925D01*
Y183332D01*
X1135475Y180332D01*
Y177865D01*
X1134110Y176500D01*
G01X1113530Y995678D02*
X1116852Y999000D01*
X1133009D01*
X1139738Y1005729D01*
Y1063562D01*
X1117100Y1086200D01*
Y1110600D01*
X1149608Y1143108D01*
Y1228988D01*
X1150420Y1229800D01*
G01X1119042Y995678D02*
Y995480D01*
X1122527Y991995D01*
X1136481D01*
X1138198Y990278D01*
Y832424D01*
G01X1123600Y1100000D02*
X1125000D01*
X1128500Y1096500D01*
Y1088156D01*
X1158100Y1058556D01*
Y1007408D01*
X1149630Y998938D01*
Y420596D01*
X1149056Y420022D01*
Y419923D01*
X1148548Y419415D01*
Y-29458D01*
X1146768Y-31238D01*
G01X1119042Y1294902D02*
X1121469Y1292475D01*
X1134767D01*
X1141700Y1285542D01*
Y1147300D01*
X1119500Y1125100D01*
G01X1113530Y1294902D02*
X1117832Y1290600D01*
X1133990D01*
X1139825Y1284765D01*
Y1153826D01*
X1137025Y1151026D01*
Y1147125D01*
X1115000Y1125100D01*
G01X1139808Y-31171D02*
X1141914Y-33277D01*
X1148148D01*
X1151228Y-30197D01*
Y-28629D01*
X1151215Y-28616D01*
Y-26093D01*
X1151228Y-26080D01*
Y419895D01*
X1151256Y419923D01*
Y420022D01*
X1151830Y420596D01*
Y998026D01*
X1160300Y1006496D01*
Y1059700D01*
X1131000Y1089000D01*
Y1093500D01*
X1133783Y1096283D01*
X1133981D01*
G01X1134002Y1092600D02*
X1137400D01*
X1159500Y1070500D01*
Y1065388D01*
X1211950Y1012938D01*
Y514908D01*
X1153455Y456413D01*
Y229359D01*
X1154599Y228215D01*
Y-30253D01*
X1149699Y-35153D01*
G01X1142293Y-37522D02*
X1142621Y-37194D01*
X1151137D01*
X1156799Y-31532D01*
Y229127D01*
X1155080Y230846D01*
Y454926D01*
X1214150Y513996D01*
Y1013850D01*
X1162000Y1066000D01*
Y1071984D01*
X1134103Y1099881D01*
G01X1215795Y181242D02*
X1217212Y182659D01*
Y222397D01*
X1225630Y230815D01*
Y242896D01*
X1213609Y254917D01*
Y380244D01*
X1238160Y404795D01*
Y522540D01*
X1237262Y523438D01*
Y669661D01*
X1229288Y677635D01*
Y1025473D01*
X1187101Y1067660D01*
Y1285399D01*
X1142800Y1329700D01*
Y1395175D01*
X1133275Y1404700D01*
X1117118D01*
X1113530Y1408288D01*
G01X1119042Y1379942D02*
X1119058D01*
X1122500Y1376500D01*
X1135000D01*
X1140000Y1371500D01*
Y1329848D01*
X1144000Y1325848D01*
Y1310000D01*
G01X1171749Y259163D02*
Y262403D01*
X1192403Y283057D01*
Y306460D01*
X1193800Y307857D01*
G01X1175400Y258800D02*
X1176100Y259500D01*
Y263253D01*
X1197070Y284223D01*
Y305828D01*
X1198100Y306858D01*
G01X1358355Y81488D02*
X1357238Y80371D01*
Y71897D01*
X1339203Y53862D01*
X1323155D01*
X1306500Y70517D01*
Y83505D01*
X1306501Y83506D01*
Y85112D01*
X1306500Y85113D01*
Y92386D01*
X1306290Y92596D01*
Y94202D01*
X1306500Y94412D01*
Y99967D01*
X1306501Y99968D01*
Y101574D01*
X1306500Y101575D01*
Y151320D01*
X1285967Y171853D01*
Y191433D01*
X1215600Y261800D01*
G01X1226045Y431102D02*
Y396181D01*
X1211134Y381270D01*
Y253567D01*
X1219962Y244739D01*
G01X1239362Y524168D02*
Y670302D01*
X1231226Y678438D01*
Y936126D01*
X1235600Y940500D01*
Y1021902D01*
X1205132Y1052370D01*
Y1227433D01*
X1205303Y1227604D01*
G01X1232842Y1140722D02*
Y1073658D01*
X1252400Y1054100D01*
G01X1312263Y95463D02*
Y98205D01*
X1319650Y105592D01*
Y118780D01*
X1313060Y125370D01*
Y150474D01*
X1290179Y173355D01*
Y191475D01*
X1276483Y205171D01*
Y205417D01*
X1254200Y227700D01*
X1253300D01*
G01X1323829Y55929D02*
X1331159Y63259D01*
Y93978D01*
X1323762Y101375D01*
Y123578D01*
X1317394Y129946D01*
Y163136D01*
X1299675Y180855D01*
Y252283D01*
X1286997Y264961D01*
Y272178D01*
X1262075Y297100D01*
G01X1336034Y82542D02*
Y94058D01*
X1328121Y101971D01*
Y128196D01*
X1328122Y128197D01*
Y129543D01*
X1320644Y137021D01*
Y171008D01*
X1302925Y188727D01*
Y253828D01*
X1290475Y266278D01*
Y273770D01*
X1259587Y304658D01*
Y578017D01*
X1251862Y585742D01*
Y691443D01*
X1254549Y694130D01*
Y870058D01*
X1266207Y881716D01*
Y987992D01*
X1263618Y990581D01*
Y990606D01*
G01X1268378Y990608D02*
Y881588D01*
X1257810Y871020D01*
Y800996D01*
X1257350Y800536D01*
Y682242D01*
X1256437Y681329D01*
Y605924D01*
X1257810Y604551D01*
Y583393D01*
X1261212Y579991D01*
Y305332D01*
X1292600Y273944D01*
Y266452D01*
X1304550Y254502D01*
Y189401D01*
X1322269Y171682D01*
Y137695D01*
X1329747Y130217D01*
Y127523D01*
X1329746Y127522D01*
Y102736D01*
X1337972Y94510D01*
Y79481D01*
X1334383Y75892D01*
G01X1271296Y986867D02*
Y882207D01*
X1260700Y871611D01*
Y801587D01*
X1258975Y799862D01*
Y680956D01*
X1258062Y680043D01*
Y606598D01*
X1260700Y603960D01*
Y582802D01*
X1262837Y580665D01*
Y306006D01*
X1294367Y274476D01*
Y266984D01*
X1306175Y255176D01*
Y190075D01*
X1324533Y171717D01*
Y142321D01*
X1326493Y140361D01*
Y137118D01*
X1326492Y137117D01*
Y135771D01*
X1331372Y130891D01*
Y126849D01*
X1331371Y126848D01*
Y103722D01*
X1340961Y94132D01*
Y78811D01*
G01X1343521Y85472D02*
Y93938D01*
X1332996Y104463D01*
Y126174D01*
X1332997Y126175D01*
Y131565D01*
X1328118Y136444D01*
Y141411D01*
X1326158Y143371D01*
Y173752D01*
X1322887Y177023D01*
Y203215D01*
X1307800Y218302D01*
Y255850D01*
X1296300Y267350D01*
Y274842D01*
X1266816Y304326D01*
Y581400D01*
X1262787Y585429D01*
Y679354D01*
X1260600Y681541D01*
Y799188D01*
X1265500Y804088D01*
Y874112D01*
X1274413Y883025D01*
Y984613D01*
G01X1272755Y1137293D02*
Y1059683D01*
X1276351Y1056087D01*
Y881051D01*
X1267623Y872323D01*
Y803912D01*
X1262225Y798514D01*
Y682916D01*
X1263210Y681931D01*
Y681930D01*
X1264412Y680728D01*
Y586636D01*
X1270448Y580600D01*
Y305207D01*
X1272106Y303549D01*
Y301743D01*
X1281928Y291921D01*
X1283734D01*
X1304945Y270710D01*
Y262655D01*
X1309425Y258175D01*
Y218976D01*
X1324512Y203889D01*
Y177934D01*
X1328179Y174267D01*
Y143649D01*
X1330339Y141489D01*
Y136747D01*
X1334621Y132465D01*
Y132240D01*
X1334622Y132239D01*
Y125501D01*
X1334621Y125500D01*
Y105137D01*
X1346081Y93677D01*
Y80671D01*
G01X1348641Y83326D02*
Y93747D01*
X1336246Y106142D01*
Y124826D01*
X1336247Y124827D01*
Y132913D01*
X1336246Y132914D01*
Y133139D01*
X1335470Y133915D01*
Y142288D01*
X1330008Y147750D01*
Y175121D01*
X1326137Y178992D01*
Y204563D01*
X1311050Y219650D01*
Y258849D01*
X1306804Y263095D01*
Y271150D01*
X1284407Y293547D01*
X1282601D01*
X1273731Y302417D01*
Y304223D01*
X1272073Y305881D01*
Y581400D01*
X1266037Y587436D01*
Y681402D01*
X1264835Y682604D01*
Y682605D01*
X1263850Y683590D01*
Y797840D01*
X1269248Y803238D01*
Y871648D01*
X1279599Y881999D01*
Y976407D01*
G01X1243200Y933700D02*
X1239443Y929943D01*
Y679545D01*
X1247989Y670999D01*
Y581276D01*
X1255761Y573504D01*
Y271861D01*
X1250500Y266600D01*
G01X1333281Y85133D02*
Y94467D01*
X1326496Y101252D01*
Y128870D01*
X1319019Y136347D01*
Y170334D01*
X1301300Y188053D01*
Y253154D01*
X1288850Y265604D01*
Y273096D01*
X1257962Y303984D01*
Y577343D01*
X1250237Y585068D01*
Y692117D01*
X1252924Y694804D01*
Y870732D01*
X1264269Y882077D01*
Y981248D01*
G01X1338215Y107586D02*
Y112926D01*
X1340338Y115049D01*
Y139719D01*
X1331866Y148191D01*
Y176271D01*
X1327762Y180375D01*
Y207338D01*
X1324470Y210630D01*
Y293153D01*
X1331667Y300350D01*
Y419331D01*
X1278523Y472475D01*
Y577677D01*
X1267662Y588538D01*
Y698613D01*
X1267829Y698780D01*
Y700386D01*
X1267662Y700553D01*
Y714097D01*
X1266462Y715297D01*
Y735315D01*
X1270873Y739726D01*
Y870974D01*
X1286633Y886734D01*
Y967747D01*
X1286000Y968380D01*
Y982200D01*
G01X1333988Y161471D02*
Y190109D01*
X1330300Y193797D01*
Y296242D01*
X1338460Y304402D01*
Y415280D01*
X1280461Y473279D01*
Y578698D01*
X1270206Y588953D01*
Y674446D01*
X1274200Y678440D01*
Y702800D01*
X1294250Y722850D01*
Y762970D01*
X1346080Y814800D01*
Y907004D01*
G01X1253511Y517606D02*
Y572642D01*
X1245789Y580364D01*
Y670087D01*
X1237243Y678633D01*
Y938243D01*
X1240583Y941583D01*
Y1023317D01*
X1239900Y1024000D01*
G01X1268400Y716100D02*
Y732463D01*
X1291194Y755257D01*
Y763893D01*
X1341219Y813918D01*
Y933282D01*
G01X1259808Y927260D02*
Y1044892D01*
X1257000Y1047700D01*
Y1165700D01*
X1260300Y1169000D01*
G01X1253338Y980784D02*
Y1044356D01*
X1254800Y1045818D01*
Y1269600D01*
G01X1256142Y1029316D02*
Y972314D01*
X1253975Y970147D01*
G01X1240314Y1139741D02*
X1240276Y1139779D01*
Y1356700D01*
G01X1334300Y771200D02*
Y719300D01*
X1287168Y672168D01*
Y624244D01*
X1289781Y621631D01*
Y601279D01*
X1287168Y598666D01*
Y587917D01*
X1289875Y585210D01*
Y477182D01*
X1347874Y419183D01*
Y300500D01*
X1342152Y294778D01*
Y154148D01*
X1352897Y143403D01*
Y135595D01*
X1349675Y132373D01*
Y114341D01*
X1346703Y111369D01*
Y107372D01*
X1352351Y101724D01*
G01X1338729Y776131D02*
X1340638Y774222D01*
Y718741D01*
X1294750Y672853D01*
Y479204D01*
X1352749Y421205D01*
Y298478D01*
X1347490Y293219D01*
Y156512D01*
X1357772Y146230D01*
Y132984D01*
X1356119Y131331D01*
Y111836D01*
X1350779Y106496D01*
G01X1338700Y771500D02*
Y719102D01*
X1293125Y673527D01*
Y478530D01*
X1351124Y420531D01*
Y299152D01*
X1345865Y293893D01*
Y155838D01*
X1356147Y145556D01*
Y133658D01*
X1354494Y132005D01*
Y116403D01*
X1348641Y110550D01*
G01X1398228Y102166D02*
X1382310Y118084D01*
Y135918D01*
X1353228Y165000D01*
Y290841D01*
X1358487Y296100D01*
Y424259D01*
X1300488Y482258D01*
Y670475D01*
X1347600Y717587D01*
Y734078D01*
G01X1398228Y96654D02*
Y97372D01*
X1379310Y116290D01*
Y134675D01*
X1350228Y163757D01*
Y292084D01*
X1355487Y297343D01*
Y423016D01*
X1297488Y481015D01*
Y671718D01*
X1344062Y718292D01*
Y737800D01*
G01X1351665Y128325D02*
Y131475D01*
X1354522Y134332D01*
Y144578D01*
X1343778Y155322D01*
Y294105D01*
X1349499Y299826D01*
Y419857D01*
X1291500Y477856D01*
Y674201D01*
X1336238Y718939D01*
Y772862D01*
X1334329Y774771D01*
Y775831D01*
G01X1412402Y110827D02*
X1407923Y115306D01*
Y125064D01*
X1397371Y135616D01*
X1396957D01*
X1365325Y167248D01*
Y427094D01*
X1313988Y478431D01*
Y631972D01*
X1321738Y639722D01*
Y664290D01*
X1335724Y678276D01*
Y691341D01*
X1354500Y710117D01*
Y747304D01*
G01X1412402Y116339D02*
X1409800Y118941D01*
Y126688D01*
X1367800Y168688D01*
Y428120D01*
X1316463Y479457D01*
Y630946D01*
X1324213Y638696D01*
Y663264D01*
X1338199Y677250D01*
Y690315D01*
X1360920Y713036D01*
Y749829D01*
G01X1426575Y96654D02*
X1422199Y101030D01*
Y153583D01*
X1380100Y195682D01*
Y419321D01*
X1318938Y480483D01*
Y629920D01*
X1326688Y637670D01*
Y662238D01*
X1340674Y676224D01*
Y689289D01*
X1368447Y717062D01*
Y790447D01*
X1375905Y797905D01*
Y1136205D01*
X1381875Y1142175D01*
Y1329525D01*
X1381800Y1329600D01*
G01X1405315Y114764D02*
X1401600Y118479D01*
Y125192D01*
X1395276Y131516D01*
X1395257D01*
X1361225Y165548D01*
Y425394D01*
X1303226Y483393D01*
Y627010D01*
X1317638Y641422D01*
Y665990D01*
X1331349Y679701D01*
Y698349D01*
X1349761Y716761D01*
Y777308D01*
X1371181Y798728D01*
Y1143681D01*
X1378625Y1151125D01*
Y1321075D01*
X1369600Y1330100D01*
G01X1405315Y120276D02*
Y124285D01*
X1404476Y125124D01*
X1404362D01*
X1396345Y133141D01*
X1395931D01*
X1362850Y166222D01*
Y426068D01*
X1305562Y483356D01*
Y627047D01*
X1319263Y640748D01*
Y665316D01*
X1333249Y679302D01*
Y697624D01*
X1351386Y715761D01*
Y776634D01*
X1372806Y798054D01*
Y1142806D01*
X1380250Y1150250D01*
Y1323450D01*
X1373700Y1330000D01*
G01X1384713Y323200D02*
Y417449D01*
X1320876Y481286D01*
Y629559D01*
X1336600Y645283D01*
Y667800D01*
X1342299Y673499D01*
Y688173D01*
X1370518Y716392D01*
Y789777D01*
X1377843Y797102D01*
Y971843D01*
X1378100Y972100D01*
G01X1388500Y1224900D02*
Y1069500D01*
X1382600Y1063600D01*
Y797712D01*
X1376844Y791956D01*
Y715344D01*
X1347249Y685749D01*
Y671447D01*
X1341550Y665748D01*
Y643231D01*
X1328909Y630590D01*
Y625557D01*
X1326352Y623000D01*
Y532048D01*
X1338100Y520300D01*
G01X1384800Y1002666D02*
Y798624D01*
X1384801Y798623D01*
Y796801D01*
X1379044Y791044D01*
Y715245D01*
X1348874Y685075D01*
Y670773D01*
X1343175Y665074D01*
Y642557D01*
X1330534Y629916D01*
Y624883D01*
X1328552Y622901D01*
Y543848D01*
X1353500Y518900D01*
G01X1433661Y120276D02*
Y156856D01*
X1420700Y169817D01*
Y422000D01*
X1323614Y519086D01*
Y628796D01*
X1339075Y644257D01*
Y666774D01*
X1344774Y672473D01*
Y686775D01*
X1373519Y715520D01*
Y761900D01*
G01X1317400Y1068000D02*
Y1065800D01*
X1312767Y1061167D01*
Y885535D01*
G01X1359350Y66350D02*
X1363758Y70758D01*
Y123018D01*
X1364017Y123277D01*
G01X1349931Y138361D02*
Y134928D01*
X1348050Y133047D01*
Y115015D01*
X1345078Y112043D01*
Y103866D01*
X1347607Y101337D01*
G01X1412402Y96654D02*
Y97202D01*
X1415017Y99817D01*
Y124972D01*
X1370275Y169714D01*
Y297075D01*
X1375700Y302500D01*
Y413400D01*
G01X1398228Y110827D02*
X1391700Y117355D01*
Y130201D01*
X1355991Y165910D01*
Y275272D01*
G01X1398228Y116339D02*
X1393816Y120751D01*
Y130584D01*
X1358573Y165827D01*
Y290900D01*
G01X1419488Y106103D02*
X1416892Y108699D01*
Y130255D01*
X1398810Y148337D01*
Y163397D01*
X1372274Y189933D01*
Y272874D01*
G01X1419488Y120276D02*
Y148544D01*
X1375273Y192759D01*
Y291965D01*
X1374338Y292900D01*
G01X1336000Y627000D02*
Y633083D01*
X1344800Y641883D01*
Y662800D01*
X1351901Y669901D01*
Y685803D01*
X1380669Y714571D01*
Y714669D01*
X1381244Y715244D01*
Y790132D01*
X1387500Y796388D01*
Y881841D01*
X1392355Y886696D01*
G01X1339404Y969600D02*
Y1025410D01*
X1364903Y1050909D01*
Y1092376D01*
X1355733Y1101546D01*
Y1241900D01*
G01X1353762Y969886D02*
X1353900Y970024D01*
Y1010769D01*
X1349829Y1014840D01*
G01X1365551Y1028250D02*
Y1048445D01*
X1367103Y1049997D01*
Y1093288D01*
X1358064Y1102327D01*
Y1141693D01*
X1360238Y1143867D01*
G01X1361074Y1114565D02*
X1360264Y1115375D01*
Y1138988D01*
X1362511Y1141235D01*
Y1168748D01*
X1365551Y1171788D01*
Y1353500D01*
G01X1426575Y102166D02*
X1424074Y104667D01*
Y155054D01*
X1388000Y191128D01*
Y431200D01*
X1395300Y438500D01*
G01X1433661Y106103D02*
X1431126Y108638D01*
Y155890D01*
X1418225Y168791D01*
Y421700D01*
G01X1433661Y100591D02*
Y101139D01*
X1429126Y105674D01*
Y126373D01*
X1427684Y127815D01*
Y155831D01*
X1414882Y168633D01*
Y397271D01*
G01X1427663Y167032D02*
X1423661Y171034D01*
Y274600D01*
X1431909Y282848D01*
Y359311D01*
G01X1383952Y717435D02*
Y788952D01*
X1395843Y800843D01*
Y927557D01*
X1391000Y932400D01*
G01X1380300Y930200D02*
Y1117600D01*
X1383900Y1121200D01*
Y1166689D01*
X1383899Y1166690D01*
G01X1440748Y96654D02*
X1443953Y99859D01*
Y172534D01*
X1432575Y183912D01*
Y273555D01*
X1444213Y285193D01*
Y349827D01*
X1444238Y349852D01*
G01X1440748Y102166D02*
X1438056Y104858D01*
Y126165D01*
X1440647Y128756D01*
Y172339D01*
X1430100Y182886D01*
Y274581D01*
X1441689Y286170D01*
Y347817D01*
X1439654Y349852D01*
G01X1490354Y106103D02*
X1487650Y108807D01*
Y127963D01*
X1472950Y142663D01*
Y459174D01*
X1526429Y512653D01*
Y561315D01*
X1474083Y613661D01*
Y764750D01*
G01X1490354Y100591D02*
X1485775Y105170D01*
Y124878D01*
X1470475Y140178D01*
Y460675D01*
X1523954Y514154D01*
Y560289D01*
X1471608Y612635D01*
Y768500D01*
G01X1456373Y168971D02*
Y450446D01*
X1521216Y515289D01*
Y559154D01*
X1468870Y611500D01*
Y828530D01*
X1447600Y849800D01*
Y909600D01*
X1448000Y910000D01*
G01X1431909Y359311D02*
Y469425D01*
X1474700Y512216D01*
Y569100D01*
G01X1463000Y490638D02*
Y491800D01*
X1469170Y497970D01*
X1494782D01*
X1515938Y519126D01*
Y558208D01*
X1464470Y609676D01*
Y826330D01*
X1442500Y848300D01*
Y941000D01*
X1448400Y946900D01*
Y1046900D01*
X1467000Y1065500D01*
Y1221800D01*
G01X1455202Y618557D02*
X1455200Y618559D01*
Y831000D01*
X1440100Y846100D01*
Y893100D01*
X1440500Y893500D01*
G01X1481938Y489926D02*
X1492741D01*
X1519016Y516201D01*
Y558242D01*
X1466670Y610588D01*
Y826955D01*
X1444900Y848725D01*
Y939500D01*
X1451800Y946400D01*
Y1004700D01*
G01X1435300Y882700D02*
Y938000D01*
X1446213Y948913D01*
Y1062300D01*
G01X1473600Y1242777D02*
Y1061355D01*
X1463616Y1051371D01*
Y969265D01*
G01X1497441Y96654D02*
X1501900Y101113D01*
Y125022D01*
X1500756Y126166D01*
Y133171D01*
X1482850Y151077D01*
Y455070D01*
X1537259Y509479D01*
Y564489D01*
X1483983Y617765D01*
Y785303D01*
X1483861Y785425D01*
Y992176D01*
X1484000Y992315D01*
G01X1497441Y102166D02*
X1500025Y104750D01*
Y123229D01*
X1497980Y125274D01*
Y132446D01*
X1480375Y150051D01*
Y456096D01*
X1534629Y510350D01*
Y563618D01*
X1481508Y616739D01*
Y784277D01*
X1481386Y784399D01*
Y995644D01*
X1481500Y995758D01*
G01X1497441Y110827D02*
X1492934Y115334D01*
Y126179D01*
X1492539Y126574D01*
Y126575D01*
X1475425Y143689D01*
Y458148D01*
X1528904Y511627D01*
Y562341D01*
X1476558Y614687D01*
Y759088D01*
G01X1518701Y106103D02*
X1521225Y108627D01*
Y130561D01*
X1494637Y157149D01*
Y453453D01*
X1546735Y505551D01*
Y568417D01*
X1498287Y616865D01*
Y705839D01*
X1494125Y710001D01*
Y929725D01*
X1497400Y933000D01*
Y1120700D01*
X1502200Y1125500D01*
Y1150000D01*
X1497400Y1154800D01*
Y1342300D01*
X1497200Y1342500D01*
G01X1518701Y100591D02*
X1523100Y104990D01*
Y131400D01*
X1496262Y158238D01*
Y452779D01*
X1548360Y504877D01*
Y569091D01*
X1499912Y617539D01*
Y706513D01*
X1495750Y710675D01*
Y929051D01*
X1499500Y932801D01*
Y1099500D01*
X1504400Y1104400D01*
Y1164600D01*
X1502000Y1167000D01*
Y1341200D01*
X1501600Y1341600D01*
Y1342300D01*
G01X1497441Y116339D02*
X1495014Y118766D01*
Y131911D01*
X1477900Y149025D01*
Y457122D01*
X1531379Y510601D01*
Y563367D01*
X1479033Y615713D01*
Y762259D01*
G01X1525787Y96654D02*
X1530237Y101104D01*
Y132100D01*
X1501212Y161125D01*
Y227912D01*
X1504700Y231400D01*
Y264200D01*
X1501361Y267539D01*
Y450876D01*
X1553310Y502825D01*
Y571143D01*
X1504862Y619591D01*
Y708565D01*
X1500700Y712727D01*
Y739478D01*
X1500539Y739639D01*
G01X1525787Y102166D02*
X1528362Y104741D01*
Y125974D01*
X1527762Y126574D01*
Y130538D01*
X1498737Y159563D01*
Y229037D01*
X1502225Y232525D01*
Y263174D01*
X1498886Y266513D01*
Y451902D01*
X1550835Y503851D01*
Y570117D01*
X1502387Y618565D01*
Y707539D01*
X1498225Y711701D01*
Y742775D01*
X1498000Y743000D01*
G01X1503394Y968179D02*
X1503469Y968104D01*
Y713831D01*
X1511300Y706000D01*
Y617026D01*
X1556048Y572278D01*
Y501690D01*
X1508925Y454567D01*
Y323200D01*
G01X1513200Y519700D02*
Y546041D01*
X1498841Y560400D01*
X1494400D01*
G01Y556100D02*
X1509838Y540662D01*
Y523238D01*
X1509800Y523200D01*
Y516100D01*
G01X1505900Y717600D02*
Y930400D01*
G01X1504200Y1171300D02*
X1507400Y1168100D01*
Y1103400D01*
X1502500Y1098500D01*
Y976500D01*
X1507400Y971600D01*
Y941800D01*
X1521200Y928000D01*
G01X1477974Y970044D02*
X1478200Y970270D01*
Y1017160D01*
X1478194Y1017166D01*
G01X1481529Y1030500D02*
Y1136065D01*
X1485833Y1140369D01*
G01X1485608Y1113628D02*
Y1133484D01*
X1491662Y1139538D01*
Y1351300D01*
G01X1568500Y438500D02*
Y544100D01*
G01X1570425Y1062000D02*
Y888475D01*
X1570500Y888400D01*
G01X1558650Y1217426D02*
Y1191000D01*
X1566550Y1183100D01*
Y1108550D01*
X1577435Y1097665D01*
Y945265D01*
X1597938Y924762D01*
Y680191D01*
X1622465Y655664D01*
Y618693D01*
X1586596Y582824D01*
Y518723D01*
G01X1579371Y166019D02*
X1590600Y177248D01*
Y389788D01*
X1577580Y402808D01*
Y608149D01*
X1580864Y611433D01*
Y674804D01*
X1587400Y681340D01*
Y912200D01*
G01X1622738Y264938D02*
X1592800Y294876D01*
Y390700D01*
X1580249Y403251D01*
Y608519D01*
X1582489Y610759D01*
Y674130D01*
X1592800Y684441D01*
Y922200D01*
X1574576Y940424D01*
Y976700D01*
G01X1703584Y166019D02*
Y182602D01*
X1702838Y183348D01*
Y316862D01*
X1601406Y418294D01*
Y515623D01*
X1601548D01*
X1602683Y516758D01*
Y518364D01*
X1602370Y518677D01*
Y593214D01*
X1625715Y616559D01*
Y658391D01*
X1602370Y681736D01*
Y908570D01*
X1608200Y914400D01*
G01X1600745Y517561D02*
Y594674D01*
X1624090Y618019D01*
Y657717D01*
X1600744Y681063D01*
Y682409D01*
X1600745Y682410D01*
Y925067D01*
X1580381Y945431D01*
Y1007066D01*
G01X1578926Y618657D02*
Y675246D01*
X1585125Y681445D01*
Y895475D01*
X1584800Y895800D01*
G01X1615494Y973179D02*
X1611939Y969624D01*
Y962964D01*
X1612745Y962158D01*
Y960552D01*
X1611939Y959746D01*
Y914681D01*
X1604985Y907727D01*
Y681420D01*
X1627340Y659065D01*
Y615885D01*
X1620551Y609096D01*
Y463952D01*
X1635332Y449171D01*
Y400969D01*
X1638807Y397494D01*
Y395393D01*
X1747550Y286650D01*
Y265000D01*
G01X1618200Y916800D02*
X1608266Y906866D01*
Y685134D01*
X1629212Y664188D01*
Y604044D01*
X1622176Y597008D01*
Y464626D01*
X1636957Y449845D01*
Y401643D01*
X1827796Y210804D01*
Y166019D01*
G01X1869500Y179134D02*
X1861000Y187634D01*
Y219500D01*
X1788500Y292000D01*
Y302900D01*
X1625426Y465974D01*
Y595660D01*
X1640515Y610749D01*
Y660685D01*
X1613600Y687600D01*
Y899600D01*
X1630938Y916938D01*
Y973335D01*
X1629094Y975179D01*
G01X1621787Y917108D02*
X1611175Y906496D01*
Y685812D01*
X1638890Y658097D01*
Y611423D01*
X1623801Y596334D01*
Y465300D01*
X1640230Y448871D01*
Y429170D01*
X1837200Y232200D01*
Y156789D01*
X1841021Y152968D01*
G01X1621138Y719238D02*
X1616164Y724212D01*
Y897291D01*
X1633600Y914727D01*
Y936300D01*
G01X1587829Y969191D02*
Y1074229D01*
X1613400Y1099800D01*
Y1236500D01*
G01X1602187Y969970D02*
X1602407Y970190D01*
Y1019359D01*
X1602400Y1019366D01*
G01X1643344Y887455D02*
X1663300Y907411D01*
Y1032200D01*
X1685100Y1054000D01*
G01X1646013Y884255D02*
X1665969Y904211D01*
Y1029838D01*
X1679300Y1043169D01*
G01X1636400Y925800D02*
Y1087400D01*
X1633138Y1090662D01*
Y1165673D01*
G01X1639644Y889755D02*
X1659600Y909711D01*
Y1032885D01*
X1690315Y1063600D01*
X1694638D01*
G01X1620059Y1128071D02*
Y1032932D01*
G01X1624500Y1349100D02*
X1624198Y1348798D01*
Y1111309D01*
G01X1711061Y518470D02*
X1709338Y520193D01*
Y686576D01*
X1718395Y695633D01*
Y784132D01*
X1734575Y800312D01*
Y872013D01*
X1668449Y938139D01*
Y1027249D01*
X1702838Y1061638D01*
Y1215300D01*
G01X1725100Y519300D02*
X1711538Y532862D01*
Y686096D01*
X1720020Y694578D01*
Y783458D01*
X1736515Y799953D01*
Y873185D01*
X1671422Y938278D01*
Y1009266D01*
G01X1704010Y898000D02*
X1732911Y869099D01*
Y800947D01*
X1716770Y784806D01*
Y696431D01*
X1707138Y686799D01*
Y676025D01*
X1704010Y672897D01*
Y649490D01*
X1705000Y648500D01*
Y618667D01*
G01X1692100Y923600D02*
Y939755D01*
X1682476Y949379D01*
Y1018929D01*
X1730379Y1066832D01*
Y1106091D01*
X1751400Y1127112D01*
Y1173900D01*
G01X1834896Y518597D02*
X1853917Y537618D01*
Y698255D01*
X1832678Y719494D01*
Y887727D01*
X1786305Y934100D01*
X1703928D01*
X1687800Y950228D01*
Y1021141D01*
X1732579Y1065920D01*
Y1105179D01*
X1755900Y1128500D01*
Y1212704D01*
G01X1690279Y1011526D02*
Y950861D01*
X1704840Y936300D01*
X1787217D01*
X1834304Y889213D01*
Y722152D01*
X1859786Y696670D01*
Y626614D01*
X1861317Y625083D01*
Y529707D01*
X1849045Y517435D01*
G01X1710617Y1231429D02*
X1710600Y1231412D01*
Y1064300D01*
X1674814Y1028514D01*
Y961977D01*
G01X1715049Y1234000D02*
Y1064949D01*
X1677055Y1026955D01*
Y954637D01*
X1677056Y954636D01*
G01X1680012Y952402D02*
X1680087Y952477D01*
Y1023983D01*
G01X1732768Y1141697D02*
X1726512Y1135441D01*
Y1069904D01*
X1691771Y1035163D01*
G01X1740000Y1346900D02*
X1740026Y1346874D01*
Y1131821D01*
X1733245Y1125040D01*
Y1115503D01*
G01X1824170Y886349D02*
X1828700Y881819D01*
Y619736D01*
X1827667Y618703D01*
G01X1823937Y890883D02*
X1830757Y884063D01*
Y717348D01*
X1839667Y708438D01*
Y612581D01*
X1840855Y611393D01*
Y606200D01*
G01X1813851Y927406D02*
Y912223D01*
X1836078Y889996D01*
Y722891D01*
X1867400Y691569D01*
Y635600D01*
X1869500Y633500D01*
G01X1819541Y921500D02*
X1837865D01*
X1877900Y961535D01*
Y1028700D01*
X1887402Y1038202D01*
Y1050193D01*
G01X1836200Y1130000D02*
X1833724Y1132476D01*
Y1156410D01*
X1842000Y1164686D01*
Y1344700D01*
G01X1864617Y1040934D02*
Y1075244D01*
X1868500Y1079127D01*
Y1110000D01*
X1840585Y1137915D01*
Y1151653D01*
M02*
